FILE_TYPE = MACRO_DRAWING;
SET COLOR_WIRE YELLOW;
SET COLOR_PROP MONO;
SET COLOR_DOT WHITE;
SET COLOR_ARC YELLOW;
SET COLOR_BODY GREEN;
SET COLOR_NOTE MONO;
SET PROP_DISPLAY VALUE;
SET PAGE_NUMBER P153;
FORCEADD OFFPAGE..1
(-7300 3725);
FORCEPROP 2 LAST $XR0 154 
J 0
(-7552 3725);
DISPLAY 0.638298 (-7552 3725);
PAINT MONO (-7552 3725);
FORCEPROP 1 LAST OFFPAGE TRUE
J 0
(-6975 3600);
PAINT GREEN (-6975 3600);
DISPLAY INVISIBLE (-6975 3600);
FORCEPROP 2 LAST CDS_LIB mstr_standard
J 0
(-7300 3725);
DISPLAY 1.531915 (-7300 3725);
PAINT ORANGE (-7300 3725);
DISPLAY INVISIBLE (-7300 3725);
FORCEPROP 1 LAST COMMENT_BODY TRUE
J 0
(-7175 3625);
DISPLAY 0.978723 (-7175 3625);
PAINT PEACH (-7175 3625);
DISPLAY INVISIBLE (-7175 3625);
FORCEPROP 2 LAST PATH I101
J 0
(-7550 3775);
DISPLAY 1.021277 (-7550 3775);
PAINT ORANGE (-7550 3775);
DISPLAY INVISIBLE (-7550 3775);
FORCEADD OFFPAGE..1
(-7300 3825);
FORCEPROP 2 LAST $XR1 153 
J 0
(-7672 3825);
DISPLAY 0.638298 (-7672 3825);
PAINT MONO (-7672 3825);
FORCEPROP 2 LAST $XR0 154 
J 0
(-7552 3825);
DISPLAY 0.638298 (-7552 3825);
PAINT MONO (-7552 3825);
FORCEPROP 1 LAST OFFPAGE TRUE
J 0
(-6975 3700);
PAINT GREEN (-6975 3700);
DISPLAY INVISIBLE (-6975 3700);
FORCEPROP 2 LAST CDS_LIB mstr_standard
J 0
(-7300 3825);
DISPLAY 1.531915 (-7300 3825);
PAINT ORANGE (-7300 3825);
DISPLAY INVISIBLE (-7300 3825);
FORCEPROP 1 LAST COMMENT_BODY TRUE
J 0
(-7175 3725);
DISPLAY 0.978723 (-7175 3725);
PAINT PEACH (-7175 3725);
DISPLAY INVISIBLE (-7175 3725);
FORCEPROP 2 LAST PATH I102
J 0
(-7550 3875);
DISPLAY 1.021277 (-7550 3875);
PAINT ORANGE (-7550 3875);
DISPLAY INVISIBLE (-7550 3875);
FORCEADD OFFPAGE..5
(-7300 3975);
FORCEPROP 2 LAST $XR1 154 
J 0
(-7675 3975);
DISPLAY 0.638298 (-7675 3975);
PAINT MONO (-7675 3975);
FORCEPROP 2 LAST $XR0 153 
J 0
(-7555 3975);
DISPLAY 0.638298 (-7555 3975);
PAINT MONO (-7555 3975);
FORCEPROP 1 LAST OFFPAGE TRUE
J 0
(-6975 3850);
PAINT GREEN (-6975 3850);
DISPLAY INVISIBLE (-6975 3850);
FORCEPROP 2 LAST CDS_LIB mstr_standard
J 1
(-7300 3975);
PAINT ORANGE (-7300 3975);
DISPLAY INVISIBLE (-7300 3975);
FORCEPROP 1 LAST COMMENT_BODY TRUE
J 0
(-7200 3900);
DISPLAY 1.170213 (-7200 3900);
PAINT GREEN (-7200 3900);
DISPLAY INVISIBLE (-7200 3900);
FORCEPROP 2 LAST PATH I103
J 0
(-7575 4025);
DISPLAY 1.021277 (-7575 4025);
PAINT ORANGE (-7575 4025);
DISPLAY INVISIBLE (-7575 4025);
FORCEADD OFFPAGE..1
(-7300 4025);
FORCEPROP 2 LAST $XR0 153 
J 0
(-7552 4025);
DISPLAY 0.638298 (-7552 4025);
PAINT MONO (-7552 4025);
FORCEPROP 2 LAST PATH I105
J 0
(-7250 4100);
DISPLAY 1.021277 (-7250 4100);
PAINT ORANGE (-7250 4100);
DISPLAY INVISIBLE (-7250 4100);
FORCEPROP 1 LAST OFFPAGE TRUE
J 0
(-6975 3900);
DISPLAY 0.872340 (-6975 3900);
PAINT GREEN (-6975 3900);
DISPLAY INVISIBLE (-6975 3900);
FORCEPROP 1 LAST COMMENT_BODY TRUE
J 0
(-7175 3925);
DISPLAY 0.872340 (-7175 3925);
PAINT GREEN (-7175 3925);
DISPLAY INVISIBLE (-7175 3925);
FORCEPROP 2 LAST CDS_LIB mstr_standard
J 0
(-7300 4025);
PAINT ORANGE (-7300 4025);
DISPLAY INVISIBLE (-7300 4025);
FORCEADD OFFPAGE..1
(-7300 4075);
FORCEPROP 2 LAST $XR0 153 
J 0
(-7552 4075);
DISPLAY 0.638298 (-7552 4075);
PAINT MONO (-7552 4075);
FORCEPROP 2 LAST PATH I107
J 0
(-7250 4150);
DISPLAY 1.021277 (-7250 4150);
PAINT ORANGE (-7250 4150);
DISPLAY INVISIBLE (-7250 4150);
FORCEPROP 2 LAST CDS_LIB mstr_standard
J 0
(-7300 4075);
PAINT ORANGE (-7300 4075);
DISPLAY INVISIBLE (-7300 4075);
FORCEPROP 1 LAST OFFPAGE TRUE
J 0
(-6975 3950);
DISPLAY 0.872340 (-6975 3950);
PAINT GREEN (-6975 3950);
DISPLAY INVISIBLE (-6975 3950);
FORCEPROP 1 LAST COMMENT_BODY TRUE
J 0
(-7175 3975);
DISPLAY 0.872340 (-7175 3975);
PAINT GREEN (-7175 3975);
DISPLAY INVISIBLE (-7175 3975);
FORCEADD RES..1
(-6500 3350);
FORCEPROP 1 LAST WATTAGE 1/16W
J 2
(-6225 3400);
DISPLAY 0.617021 (-6225 3400);
PAINT SKYBLUE (-6225 3400);
FORCEPROP 1 LAST PACK_TYPE 0402
J 0
(-6300 3275);
DISPLAY 0.617021 (-6300 3275);
PAINT SKYBLUE (-6300 3275);
FORCEPROP 1 LAST PART_NUMBER G21796-074
J 0
(-6600 3275);
DISPLAY 0.617021 (-6600 3275);
PAINT BLUE (-6600 3275);
FORCEPROP 1 LAST TOLERANCE 1%
J 0
(-6450 3400);
DISPLAY 0.617021 (-6450 3400);
PAINT SKYBLUE (-6450 3400);
FORCEPROP 1 LAST VALUE 33.2
J 2
(-6500 3400);
DISPLAY 0.617021 (-6500 3400);
PAINT SKYBLUE (-6500 3400);
FORCEPROP 1 LAST LOCATION R7F37
J 0
(-6750 3400);
DISPLAY 0.617021 (-6750 3400);
PAINT AQUA (-6750 3400);
FORCEPROP 1 LAST MATERIAL CHIP
J 0
(-6750 3275);
DISPLAY 0.617021 (-6750 3275);
PAINT SKYBLUE (-6750 3275);
FORCEPROP 1 LASTPIN (-6600 3350) $PN 1
J 0
(-6588 3362);
DISPLAY 0.787234 (-6588 3362);
PAINT ORANGE (-6588 3362);
FORCEPROP 1 LASTPIN (-6400 3350) $PN 2
J 0
(-6438 3362);
DISPLAY 0.787234 (-6438 3362);
PAINT ORANGE (-6438 3362);
FORCEPROP 2 LAST CDS_LIB mstr_discrete
J 0
(-6500 3350);
PAINT ORANGE (-6500 3350);
DISPLAY INVISIBLE (-6500 3350);
FORCEPROP 1 LAST PATH I108
J 0
(-6550 3500);
DISPLAY 0.978723 (-6550 3500);
PAINT WHITE (-6550 3500);
DISPLAY INVISIBLE (-6550 3500);
FORCEPROP 2 LAST BOM_COST MIO_BIOS_MEM
J 0
(-6550 3500);
DISPLAY 1.021277 (-6550 3500);
PAINT ORANGE (-6550 3500);
DISPLAY INVISIBLE (-6550 3500);
FORCEPROP 2 LAST ROOM SB_SPI
J 0
(-6550 3450);
DISPLAY 1.021277 (-6550 3450);
PAINT ORANGE (-6550 3450);
DISPLAY INVISIBLE (-6550 3450);
FORCEPROP 2 LAST SEC 1
J 0
(-6550 3550);
PAINT MONO (-6550 3550);
DISPLAY INVISIBLE (-6550 3550);
FORCEPROP 2 LAST SEC_TYPE 0402
J 0
(-6550 3550);
DISPLAY 1.021277 (-6550 3550);
PAINT ORANGE (-6550 3550);
DISPLAY INVISIBLE (-6550 3550);
FORCEADD RES..1
(-6475 3075);
FORCEPROP 1 LAST VALUE 33.2
J 2
(-6500 3150);
DISPLAY 0.617021 (-6500 3150);
PAINT SKYBLUE (-6500 3150);
FORCEPROP 1 LAST TOLERANCE 1%
J 0
(-6450 3150);
DISPLAY 0.617021 (-6450 3150);
PAINT SKYBLUE (-6450 3150);
FORCEPROP 1 LAST MATERIAL CHIP
J 0
(-6750 3000);
DISPLAY 0.617021 (-6750 3000);
PAINT SKYBLUE (-6750 3000);
FORCEPROP 1 LAST LOCATION R7F3
J 0
(-6750 3150);
DISPLAY 0.617021 (-6750 3150);
PAINT AQUA (-6750 3150);
FORCEPROP 1 LASTPIN (-6575 3075) $PN 1
J 0
(-6563 3087);
DISPLAY 0.787234 (-6563 3087);
PAINT ORANGE (-6563 3087);
FORCEPROP 1 LAST PART_NUMBER G21796-074
J 0
(-6600 3000);
DISPLAY 0.617021 (-6600 3000);
PAINT BLUE (-6600 3000);
FORCEPROP 1 LAST WATTAGE 1/16W
J 2
(-6225 3150);
DISPLAY 0.617021 (-6225 3150);
PAINT SKYBLUE (-6225 3150);
FORCEPROP 1 LASTPIN (-6375 3075) $PN 2
J 0
(-6413 3087);
DISPLAY 0.787234 (-6413 3087);
PAINT ORANGE (-6413 3087);
FORCEPROP 1 LAST PACK_TYPE 0402
J 0
(-6300 3000);
DISPLAY 0.617021 (-6300 3000);
PAINT SKYBLUE (-6300 3000);
FORCEPROP 2 LAST BOM_COST MIO_BIOS_MEM
J 0
(-6525 3225);
DISPLAY 1.021277 (-6525 3225);
PAINT ORANGE (-6525 3225);
DISPLAY INVISIBLE (-6525 3225);
FORCEPROP 2 LAST CDS_LOCATION R7F3
J 0
(-6525 3125);
DISPLAY 0.617021 (-6525 3125);
PAINT AQUA (-6525 3125);
DISPLAY INVISIBLE (-6525 3125);
FORCEPROP 1 LAST PATH I109
J 0
(-6525 3225);
DISPLAY 0.978723 (-6525 3225);
PAINT WHITE (-6525 3225);
DISPLAY INVISIBLE (-6525 3225);
FORCEPROP 2 LAST NO_XNET_CONNECTION 1
J 0
(-6525 3275);
PAINT MONO (-6525 3275);
DISPLAY INVISIBLE (-6525 3275);
FORCEPROP 2 LAST ROOM SB_SPI
J 0
(-6525 3175);
DISPLAY 1.021277 (-6525 3175);
PAINT ORANGE (-6525 3175);
DISPLAY INVISIBLE (-6525 3175);
FORCEPROP 2 LAST CDS_LIB mstr_discrete
J 0
(-6475 3075);
PAINT ORANGE (-6475 3075);
DISPLAY INVISIBLE (-6475 3075);
FORCEPROP 2 LAST SEC 1
J 0
(-6525 3275);
PAINT MONO (-6525 3275);
DISPLAY INVISIBLE (-6525 3275);
FORCEPROP 2 LAST SEC_TYPE 0402
J 0
(-6525 3275);
DISPLAY 1.021277 (-6525 3275);
PAINT ORANGE (-6525 3275);
DISPLAY INVISIBLE (-6525 3275);
FORCEADD OFFPAGE..1
(-7375 3350);
FORCEPROP 2 LAST $XR1 153 
J 0
(-7747 3350);
DISPLAY 0.638298 (-7747 3350);
PAINT MONO (-7747 3350);
FORCEPROP 2 LAST $XR0 154 
J 0
(-7627 3350);
DISPLAY 0.638298 (-7627 3350);
PAINT MONO (-7627 3350);
FORCEPROP 1 LAST OFFPAGE TRUE
J 0
(-7050 3225);
DISPLAY 0.872340 (-7050 3225);
PAINT GREEN (-7050 3225);
DISPLAY INVISIBLE (-7050 3225);
FORCEPROP 2 LAST CDS_LIB mstr_standard
J 0
(-7375 3350);
PAINT ORANGE (-7375 3350);
DISPLAY INVISIBLE (-7375 3350);
FORCEPROP 2 LAST PATH I110
J 0
(-7325 3425);
DISPLAY 1.021277 (-7325 3425);
PAINT ORANGE (-7325 3425);
DISPLAY INVISIBLE (-7325 3425);
FORCEPROP 1 LAST COMMENT_BODY TRUE
J 0
(-7250 3250);
DISPLAY 0.872340 (-7250 3250);
PAINT GREEN (-7250 3250);
DISPLAY INVISIBLE (-7250 3250);
FORCEADD OFFPAGE..1
(-7375 3075);
FORCEPROP 2 LAST $XR1 153 
J 0
(-7747 3075);
DISPLAY 0.638298 (-7747 3075);
PAINT MONO (-7747 3075);
FORCEPROP 2 LAST $XR0 154 
J 0
(-7627 3075);
DISPLAY 0.638298 (-7627 3075);
PAINT MONO (-7627 3075);
FORCEPROP 1 LAST OFFPAGE TRUE
J 0
(-7050 2950);
DISPLAY 0.872340 (-7050 2950);
PAINT GREEN (-7050 2950);
DISPLAY INVISIBLE (-7050 2950);
FORCEPROP 2 LAST CDS_LIB mstr_standard
J 0
(-7375 3075);
PAINT ORANGE (-7375 3075);
DISPLAY INVISIBLE (-7375 3075);
FORCEPROP 1 LAST COMMENT_BODY TRUE
J 0
(-7250 2975);
DISPLAY 0.872340 (-7250 2975);
PAINT GREEN (-7250 2975);
DISPLAY INVISIBLE (-7250 2975);
FORCEPROP 2 LAST PATH I111
J 0
(-7325 3150);
DISPLAY 1.021277 (-7325 3150);
PAINT ORANGE (-7325 3150);
DISPLAY INVISIBLE (-7325 3150);
FORCEADD CAP_A..1
(-3925 4500);
FORCEPROP 1 LAST VOLTAGE 6.3V
J 0
(-3875 4500);
DISPLAY 0.617021 (-3875 4500);
PAINT SKYBLUE (-3875 4500);
FORCEPROP 1 LAST PACK_TYPE 0402V
J 0
(-3875 4300);
DISPLAY 0.617021 (-3875 4300);
PAINT SKYBLUE (-3875 4300);
FORCEPROP 1 LAST LOCATION C7F2
J 0
(-3875 4600);
DISPLAY 0.617021 (-3875 4600);
PAINT AQUA (-3875 4600);
FORCEPROP 1 LASTPIN (-3925 4600) $PN 1
J 0
(-3915 4580);
DISPLAY 0.617021 (-3915 4580);
PAINT ORANGE (-3915 4580);
FORCEPROP 1 LAST VALUE 1.0UF
J 0
(-3875 4550);
DISPLAY 0.617021 (-3875 4550);
PAINT SKYBLUE (-3875 4550);
FORCEPROP 1 LAST TOLERANCE 10%
J 0
(-3875 4450);
DISPLAY 0.617021 (-3875 4450);
PAINT SKYBLUE (-3875 4450);
FORCEPROP 1 LASTPIN (-3925 4400) $PN 2
J 0
(-3915 4380);
DISPLAY 0.617021 (-3915 4380);
PAINT ORANGE (-3915 4380);
FORCEPROP 1 LAST PART_NUMBER D97712-004
J 0
(-3875 4350);
DISPLAY 0.617021 (-3875 4350);
PAINT BLUE (-3875 4350);
FORCEPROP 1 LAST MATERIAL X6S
J 0
(-3875 4400);
DISPLAY 0.617021 (-3875 4400);
PAINT SKYBLUE (-3875 4400);
FORCEPROP 2 LAST ROOM SB_SPI
J 0
(-3875 4650);
DISPLAY 1.021277 (-3875 4650);
PAINT ORANGE (-3875 4650);
DISPLAY INVISIBLE (-3875 4650);
FORCEPROP 1 LAST PATH I130
J 0
(-3875 4650);
DISPLAY 0.978723 (-3875 4650);
PAINT WHITE (-3875 4650);
DISPLAY INVISIBLE (-3875 4650);
FORCEPROP 2 LAST SEC 1
J 0
(-3875 4700);
PAINT MONO (-3875 4700);
DISPLAY INVISIBLE (-3875 4700);
FORCEPROP 2 LAST SEC_TYPE 0402V
J 0
(-3875 4700);
DISPLAY 1.021277 (-3875 4700);
PAINT ORANGE (-3875 4700);
DISPLAY INVISIBLE (-3875 4700);
FORCEPROP 2 LAST CDS_SEC 1
J 0
(-3875 4650);
PAINT ORANGE (-3875 4650);
DISPLAY INVISIBLE (-3875 4650);
FORCEPROP 2 LAST BOM_COST MIO_BIOS_MEM
J 0
(-3875 4700);
DISPLAY 1.021277 (-3875 4700);
PAINT ORANGE (-3875 4700);
DISPLAY INVISIBLE (-3875 4700);
FORCEPROP 2 LAST NO_XNET_CONNECTION 1
J 0
(-3875 4700);
PAINT MONO (-3875 4700);
DISPLAY INVISIBLE (-3875 4700);
FORCEPROP 2 LAST CDS_LOCATION C7F2
J 0
(-3875 4600);
DISPLAY 0.617021 (-3875 4600);
PAINT AQUA (-3875 4600);
DISPLAY INVISIBLE (-3875 4600);
FORCEPROP 2 LAST CDS_LIB dev_discrete
J 0
(-3925 4500);
PAINT ORANGE (-3925 4500);
DISPLAY INVISIBLE (-3925 4500);
FORCEADD CAP_A..1
(-3625 4500);
FORCEPROP 1 LAST TOLERANCE 10%
J 0
(-3575 4450);
DISPLAY 0.617021 (-3575 4450);
PAINT SKYBLUE (-3575 4450);
FORCEPROP 1 LAST VOLTAGE 25V
J 0
(-3575 4500);
DISPLAY 0.617021 (-3575 4500);
PAINT SKYBLUE (-3575 4500);
FORCEPROP 1 LASTPIN (-3625 4400) $PN 2
J 0
(-3615 4380);
DISPLAY 0.617021 (-3615 4380);
PAINT ORANGE (-3615 4380);
FORCEPROP 1 LASTPIN (-3625 4600) $PN 1
J 0
(-3615 4580);
DISPLAY 0.617021 (-3615 4580);
PAINT ORANGE (-3615 4580);
FORCEPROP 1 LAST PART_NUMBER A36096-045
J 0
(-3575 4350);
DISPLAY 0.617021 (-3575 4350);
PAINT BLUE (-3575 4350);
FORCEPROP 1 LAST MATERIAL X7R
J 0
(-3575 4400);
DISPLAY 0.617021 (-3575 4400);
PAINT SKYBLUE (-3575 4400);
FORCEPROP 1 LAST PACK_TYPE 0402V
J 0
(-3575 4300);
DISPLAY 0.617021 (-3575 4300);
PAINT SKYBLUE (-3575 4300);
FORCEPROP 1 LAST VALUE 0.01UF
J 0
(-3575 4550);
DISPLAY 0.617021 (-3575 4550);
PAINT SKYBLUE (-3575 4550);
FORCEPROP 1 LAST LOCATION C7F1
J 0
(-3575 4600);
DISPLAY 0.617021 (-3575 4600);
PAINT AQUA (-3575 4600);
FORCEPROP 2 LAST ROOM SB_SPI
J 0
(-3575 4650);
DISPLAY 1.021277 (-3575 4650);
PAINT ORANGE (-3575 4650);
DISPLAY INVISIBLE (-3575 4650);
FORCEPROP 1 LAST PATH I131
J 0
(-3575 4650);
DISPLAY 0.978723 (-3575 4650);
PAINT WHITE (-3575 4650);
DISPLAY INVISIBLE (-3575 4650);
FORCEPROP 2 LAST SEC 1
J 0
(-3575 4700);
PAINT MONO (-3575 4700);
DISPLAY INVISIBLE (-3575 4700);
FORCEPROP 2 LAST SEC_TYPE 0402V
J 0
(-3575 4700);
DISPLAY 1.021277 (-3575 4700);
PAINT ORANGE (-3575 4700);
DISPLAY INVISIBLE (-3575 4700);
FORCEPROP 2 LAST CDS_SEC 1
J 0
(-3575 4650);
PAINT ORANGE (-3575 4650);
DISPLAY INVISIBLE (-3575 4650);
FORCEPROP 2 LAST BOM_COST MIO_BIOS_MEM
J 0
(-3575 4700);
DISPLAY 1.021277 (-3575 4700);
PAINT ORANGE (-3575 4700);
DISPLAY INVISIBLE (-3575 4700);
FORCEPROP 2 LAST NO_XNET_CONNECTION 1
J 0
(-3575 4700);
PAINT MONO (-3575 4700);
DISPLAY INVISIBLE (-3575 4700);
FORCEPROP 2 LAST CDS_LOCATION C7F1
J 0
(-3575 4600);
DISPLAY 0.617021 (-3575 4600);
PAINT AQUA (-3575 4600);
DISPLAY INVISIBLE (-3575 4600);
FORCEPROP 2 LAST CDS_LIB dev_discrete
J 0
(-3625 4500);
PAINT ORANGE (-3625 4500);
DISPLAY INVISIBLE (-3625 4500);
FORCEADD GND..1
(-3625 4200);
FORCEPROP 3 LASTPIN (-3625 4250) SIG_NAME GND\g
J 0
(-3615 4260);
DISPLAY 0.659574 (-3615 4260);
PAINT MONO (-3615 4260);
DISPLAY INVISIBLE (-3615 4260);
FORCEPROP 1 LAST HDL_POWER GND
J 0
(-3625 4350);
DISPLAY 0.872340 (-3625 4350);
PAINT GREEN (-3625 4350);
DISPLAY INVISIBLE (-3625 4350);
FORCEPROP 1 LAST PATH I133
J 0
(-3550 4200);
DISPLAY 0.872340 (-3550 4200);
PAINT AQUA (-3550 4200);
DISPLAY INVISIBLE (-3550 4200);
FORCEPROP 1 LAST SIZE 1B
J 0
(-3550 4150);
DISPLAY 0.872340 (-3550 4150);
PAINT AQUA (-3550 4150);
DISPLAY INVISIBLE (-3550 4150);
FORCEPROP 1 LAST VOLTAGE 0.0V
J 0
(-3670 4157);
DISPLAY 0.340426 (-3670 4157);
PAINT SKYBLUE (-3670 4157);
DISPLAY INVISIBLE (-3670 4157);
FORCEPROP 2 LAST CDS_LIB mstr_symbols
J 0
(-3625 4200);
PAINT ORANGE (-3625 4200);
DISPLAY INVISIBLE (-3625 4200);
FORCEPROP 1 LAST BODY_TYPE PLUMBING
J 0
(-3670 4157);
DISPLAY 0.340426 (-3670 4157);
PAINT GREEN (-3670 4157);
DISPLAY INVISIBLE (-3670 4157);
FORCEADD CAP_A..1
(-3625 2400);
FORCEPROP 1 LAST MATERIAL X7R
J 0
(-3575 2300);
DISPLAY 0.617021 (-3575 2300);
PAINT SKYBLUE (-3575 2300);
FORCEPROP 1 LASTPIN (-3625 2500) $PN 1
J 0
(-3615 2480);
DISPLAY 0.617021 (-3615 2480);
PAINT ORANGE (-3615 2480);
FORCEPROP 1 LAST TOLERANCE 10%
J 0
(-3575 2350);
DISPLAY 0.617021 (-3575 2350);
PAINT SKYBLUE (-3575 2350);
FORCEPROP 1 LASTPIN (-3625 2300) $PN 2
J 0
(-3615 2280);
DISPLAY 0.617021 (-3615 2280);
PAINT ORANGE (-3615 2280);
FORCEPROP 1 LAST VOLTAGE 25V
J 0
(-3575 2400);
DISPLAY 0.617021 (-3575 2400);
PAINT SKYBLUE (-3575 2400);
FORCEPROP 1 LAST VALUE 0.01UF
J 0
(-3575 2450);
DISPLAY 0.617021 (-3575 2450);
PAINT SKYBLUE (-3575 2450);
FORCEPROP 1 LAST LOCATION C3T5
J 0
(-3575 2500);
DISPLAY 0.617021 (-3575 2500);
PAINT AQUA (-3575 2500);
FORCEPROP 1 LAST PART_NUMBER A36096-045
J 0
(-3575 2250);
DISPLAY 0.617021 (-3575 2250);
PAINT BLUE (-3575 2250);
FORCEPROP 1 LAST PACK_TYPE 0402V
J 0
(-3575 2200);
DISPLAY 0.617021 (-3575 2200);
PAINT SKYBLUE (-3575 2200);
FORCEPROP 0 LAST GROUP NI_BIOS_ROM2
J 0
(-3575 2100);
DISPLAY 0.638298 (-3575 2100);
PAINT BROWN (-3575 2100);
DISPLAY BOTH (-3575 2100);
FORCEPROP 2 LAST CDS_LIB dev_discrete
J 0
(-3625 2400);
PAINT ORANGE (-3625 2400);
DISPLAY INVISIBLE (-3625 2400);
FORCEPROP 2 LAST CDS_LOCATION C3T5
J 0
(-3575 2500);
DISPLAY 0.617021 (-3575 2500);
PAINT AQUA (-3575 2500);
DISPLAY INVISIBLE (-3575 2500);
FORCEPROP 2 LAST ROOM SB_SPI
J 0
(-3575 2550);
DISPLAY 1.021277 (-3575 2550);
PAINT ORANGE (-3575 2550);
DISPLAY INVISIBLE (-3575 2550);
FORCEPROP 1 LAST PATH I136
J 0
(-3575 2550);
DISPLAY 0.978723 (-3575 2550);
PAINT WHITE (-3575 2550);
DISPLAY INVISIBLE (-3575 2550);
FORCEPROP 2 LAST CDS_SEC 1
J 0
(-3575 2550);
PAINT ORANGE (-3575 2550);
DISPLAY INVISIBLE (-3575 2550);
FORCEPROP 2 LAST BOM_COST MIO_BIOS_MEM
J 0
(-3575 2600);
DISPLAY 1.021277 (-3575 2600);
PAINT ORANGE (-3575 2600);
DISPLAY INVISIBLE (-3575 2600);
FORCEPROP 2 LAST NO_XNET_CONNECTION 1
J 0
(-3575 2600);
PAINT MONO (-3575 2600);
DISPLAY INVISIBLE (-3575 2600);
FORCEPROP 2 LAST SEC_TYPE 0402V
J 0
(-3575 2600);
DISPLAY 1.021277 (-3575 2600);
PAINT ORANGE (-3575 2600);
DISPLAY INVISIBLE (-3575 2600);
FORCEPROP 2 LAST SEC 1
J 0
(-3575 2600);
PAINT MONO (-3575 2600);
DISPLAY INVISIBLE (-3575 2600);
FORCEADD CAP_A..1
(-3925 2400);
FORCEPROP 1 LAST TOLERANCE 10%
J 0
(-3875 2350);
DISPLAY 0.617021 (-3875 2350);
PAINT SKYBLUE (-3875 2350);
FORCEPROP 1 LASTPIN (-3925 2500) $PN 1
J 0
(-3915 2480);
DISPLAY 0.787234 (-3915 2480);
PAINT ORANGE (-3915 2480);
FORCEPROP 1 LASTPIN (-3925 2300) $PN 2
J 0
(-3915 2280);
DISPLAY 0.787234 (-3915 2280);
PAINT ORANGE (-3915 2280);
FORCEPROP 1 LAST MATERIAL X6S
J 0
(-3875 2300);
DISPLAY 0.617021 (-3875 2300);
PAINT SKYBLUE (-3875 2300);
FORCEPROP 1 LAST VOLTAGE 6.3V
J 0
(-3875 2400);
DISPLAY 0.617021 (-3875 2400);
PAINT SKYBLUE (-3875 2400);
FORCEPROP 1 LAST VALUE 1.0UF
J 0
(-3875 2450);
DISPLAY 0.617021 (-3875 2450);
PAINT SKYBLUE (-3875 2450);
FORCEPROP 1 LAST LOCATION C3T4
J 0
(-3875 2500);
DISPLAY 0.617021 (-3875 2500);
PAINT AQUA (-3875 2500);
FORCEPROP 1 LAST PACK_TYPE 0402V
J 0
(-3875 2200);
DISPLAY 0.617021 (-3875 2200);
PAINT SKYBLUE (-3875 2200);
FORCEPROP 0 LAST GROUP NI_BIOS_ROM2
J 0
(-3900 2150);
DISPLAY 0.638298 (-3900 2150);
PAINT BROWN (-3900 2150);
DISPLAY BOTH (-3900 2150);
FORCEPROP 1 LAST PART_NUMBER D97712-004
J 0
(-3875 2250);
DISPLAY 0.617021 (-3875 2250);
PAINT BLUE (-3875 2250);
FORCEPROP 2 LAST SEC_TYPE 0402V
J 0
(-3875 2600);
DISPLAY 1.021277 (-3875 2600);
PAINT ORANGE (-3875 2600);
DISPLAY INVISIBLE (-3875 2600);
FORCEPROP 2 LAST SEC 1
J 0
(-3875 2600);
PAINT MONO (-3875 2600);
DISPLAY INVISIBLE (-3875 2600);
FORCEPROP 2 LAST CDS_LOCATION C3T4
J 0
(-3875 2500);
DISPLAY 0.617021 (-3875 2500);
PAINT AQUA (-3875 2500);
DISPLAY INVISIBLE (-3875 2500);
FORCEPROP 2 LAST CDS_LIB dev_discrete
J 0
(-3925 2400);
PAINT ORANGE (-3925 2400);
DISPLAY INVISIBLE (-3925 2400);
FORCEPROP 2 LAST ROOM SB_SPI
J 0
(-3875 2550);
DISPLAY 1.021277 (-3875 2550);
PAINT ORANGE (-3875 2550);
DISPLAY INVISIBLE (-3875 2550);
FORCEPROP 1 LAST PATH I138
J 0
(-3875 2550);
DISPLAY 0.978723 (-3875 2550);
PAINT WHITE (-3875 2550);
DISPLAY INVISIBLE (-3875 2550);
FORCEPROP 2 LAST BOM_COST MIO_BIOS_MEM
J 0
(-3875 2600);
DISPLAY 1.021277 (-3875 2600);
PAINT ORANGE (-3875 2600);
DISPLAY INVISIBLE (-3875 2600);
FORCEPROP 2 LAST NO_XNET_CONNECTION 1
J 0
(-3875 2600);
PAINT MONO (-3875 2600);
DISPLAY INVISIBLE (-3875 2600);
FORCEADD GND..1
(-3625 2100);
FORCEPROP 3 LASTPIN (-3625 2150) SIG_NAME GND\g
J 0
(-3615 2160);
DISPLAY 0.659574 (-3615 2160);
PAINT MONO (-3615 2160);
DISPLAY INVISIBLE (-3615 2160);
FORCEPROP 1 LAST BODY_TYPE PLUMBING
J 0
(-3670 2057);
DISPLAY 0.340426 (-3670 2057);
PAINT GREEN (-3670 2057);
DISPLAY INVISIBLE (-3670 2057);
FORCEPROP 2 LAST CDS_LIB mstr_symbols
J 0
(-3625 2100);
PAINT ORANGE (-3625 2100);
DISPLAY INVISIBLE (-3625 2100);
FORCEPROP 1 LAST VOLTAGE 0.0V
J 0
(-3670 2057);
DISPLAY 0.340426 (-3670 2057);
PAINT SKYBLUE (-3670 2057);
DISPLAY INVISIBLE (-3670 2057);
FORCEPROP 1 LAST HDL_POWER GND
J 0
(-3625 2250);
DISPLAY 0.872340 (-3625 2250);
PAINT GREEN (-3625 2250);
DISPLAY INVISIBLE (-3625 2250);
FORCEPROP 1 LAST SIZE 1B
J 0
(-3550 2050);
DISPLAY 0.872340 (-3550 2050);
PAINT AQUA (-3550 2050);
DISPLAY INVISIBLE (-3550 2050);
FORCEPROP 1 LAST PATH I139
J 0
(-3550 2100);
DISPLAY 0.872340 (-3550 2100);
PAINT AQUA (-3550 2100);
DISPLAY INVISIBLE (-3550 2100);
FORCEADD RES..1
(-1450 4425);
FORCEPROP 1 LAST TOLERANCE 1%
J 0
(-1700 4375);
DISPLAY 0.617021 (-1700 4375);
PAINT SKYBLUE (-1700 4375);
FORCEPROP 1 LAST VALUE 10.0K
J 2
(-1475 4375);
DISPLAY 0.617021 (-1475 4375);
PAINT SKYBLUE (-1475 4375);
FORCEPROP 1 LAST WATTAGE 1/16W
J 2
(-1300 4375);
DISPLAY 0.617021 (-1300 4375);
PAINT SKYBLUE (-1300 4375);
FORCEPROP 1 LAST PART_NUMBER G21796-016
J 0
(-1450 4475);
DISPLAY 0.617021 (-1450 4475);
PAINT BLUE (-1450 4475);
FORCEPROP 1 LAST MATERIAL CHIP
J 0
(-1275 4375);
DISPLAY 0.617021 (-1275 4375);
PAINT SKYBLUE (-1275 4375);
FORCEPROP 1 LAST LOCATION R7F32
J 0
(-1650 4475);
DISPLAY 0.617021 (-1650 4475);
PAINT AQUA (-1650 4475);
FORCEPROP 1 LASTPIN (-1350 4425) $PN 2
J 0
(-1388 4437);
DISPLAY 0.617021 (-1388 4437);
PAINT ORANGE (-1388 4437);
FORCEPROP 1 LASTPIN (-1550 4425) $PN 1
J 0
(-1538 4437);
DISPLAY 0.617021 (-1538 4437);
PAINT ORANGE (-1538 4437);
FORCEPROP 1 LAST PACK_TYPE 0402
J 0
(-1150 4375);
DISPLAY 0.617021 (-1150 4375);
PAINT SKYBLUE (-1150 4375);
FORCEPROP 2 LAST CDS_LOCATION R7F32
J 0
(-1475 4475);
DISPLAY 0.617021 (-1475 4475);
PAINT AQUA (-1475 4475);
DISPLAY INVISIBLE (-1475 4475);
FORCEPROP 2 LAST ROOM SB_SPI
J 0
(-1475 4525);
DISPLAY 1.021277 (-1475 4525);
PAINT ORANGE (-1475 4525);
DISPLAY INVISIBLE (-1475 4525);
FORCEPROP 2 LAST CDS_LIB mstr_discrete
J 0
(-1450 4425);
PAINT ORANGE (-1450 4425);
DISPLAY INVISIBLE (-1450 4425);
FORCEPROP 2 LAST BOM_COST MIO_BIOS_MEM
J 0
(-1475 4575);
DISPLAY 1.021277 (-1475 4575);
PAINT ORANGE (-1475 4575);
DISPLAY INVISIBLE (-1475 4575);
FORCEPROP 1 LAST PATH I140
J 0
(-1500 4575);
DISPLAY 0.978723 (-1500 4575);
PAINT WHITE (-1500 4575);
DISPLAY INVISIBLE (-1500 4575);
FORCEPROP 2 LAST SEC_TYPE 0402
J 0
(-1500 4625);
DISPLAY 1.021277 (-1500 4625);
PAINT ORANGE (-1500 4625);
DISPLAY INVISIBLE (-1500 4625);
FORCEPROP 2 LAST SEC 1
J 0
(-1500 4625);
PAINT MONO (-1500 4625);
DISPLAY INVISIBLE (-1500 4625);
FORCEPROP 2 LAST NO_XNET_CONNECTION 1
J 0
(-1500 4625);
PAINT MONO (-1500 4625);
DISPLAY INVISIBLE (-1500 4625);
FORCEADD P3V3_STBY..1
(-1750 4625);
FORCEPROP 3 LASTPIN (-1750 4575) SIG_NAME P3V3_STBY\g
J 0
(-1740 4585);
DISPLAY 0.659574 (-1740 4585);
PAINT MONO (-1740 4585);
DISPLAY INVISIBLE (-1740 4585);
FORCEPROP 1 LAST HDL_POWER P3V3_STBY
J 0
(-2050 4500);
DISPLAY 0.872340 (-2050 4500);
PAINT ORANGE (-2050 4500);
DISPLAY INVISIBLE (-2050 4500);
FORCEPROP 1 LAST BODY_TYPE PLUMBING
J 0
(-1795 4582);
DISPLAY 0.340426 (-1795 4582);
PAINT GREEN (-1795 4582);
DISPLAY INVISIBLE (-1795 4582);
FORCEPROP 1 LAST VOLTAGE 3.3V
J 0
(-1795 4582);
DISPLAY 0.340426 (-1795 4582);
PAINT SKYBLUE (-1795 4582);
DISPLAY INVISIBLE (-1795 4582);
FORCEPROP 1 LAST PATH I141
J 0
(-1705 4627);
DISPLAY 0.340426 (-1705 4627);
PAINT GREEN (-1705 4627);
DISPLAY INVISIBLE (-1705 4627);
FORCEPROP 2 LAST CDS_LIB mstr_symbols
J 0
(-1750 4625);
PAINT ORANGE (-1750 4625);
DISPLAY INVISIBLE (-1750 4625);
FORCEPROP 1 LAST SIZE 1B
J 0
(-1705 4647);
DISPLAY 0.340426 (-1705 4647);
PAINT GREEN (-1705 4647);
DISPLAY INVISIBLE (-1705 4647);
FORCEADD OFFPAGE..2
(-675 4425);
FORCEPROP 2 LAST $XR0 153 
J 0
(-486 4425);
DISPLAY 0.638298 (-486 4425);
PAINT MONO (-486 4425);
FORCEPROP 1 LAST COMMENT_BODY TRUE
J 0
(-720 4330);
DISPLAY 0.872340 (-720 4330);
PAINT GREEN (-720 4330);
DISPLAY INVISIBLE (-720 4330);
FORCEPROP 2 LAST CDS_LIB mstr_standard
J 0
(-675 4425);
PAINT ORANGE (-675 4425);
DISPLAY INVISIBLE (-675 4425);
FORCEPROP 2 LAST PATH I144
J 0
(-625 4500);
DISPLAY 1.021277 (-625 4500);
PAINT ORANGE (-625 4500);
DISPLAY INVISIBLE (-625 4500);
FORCEPROP 1 LAST OFFPAGE TRUE
J 0
(-350 4300);
DISPLAY 0.872340 (-350 4300);
PAINT GREEN (-350 4300);
DISPLAY INVISIBLE (-350 4300);
FORCEADD W25Q256..1
(-4700 3975);
FORCEPROP 2 LASTPIN (-5250 4075) $PN 1
J 2
(-5260 4085);
DISPLAY 0.617021 (-5260 4085);
PAINT ORANGE (-5260 4085);
FORCEPROP 1 LAST PART_NUMBER H25002-001
J 0
(-5200 3475);
DISPLAY 0.617021 (-5200 3475);
PAINT BLUE (-5200 3475);
FORCEPROP 1 LAST MATERIAL IC
J 0
(-5200 4375);
DISPLAY 0.617021 (-5200 4375);
PAINT SKYBLUE (-5200 4375);
FORCEPROP 2 LASTPIN (-5250 4025) $PN 9
J 2
(-5260 4035);
DISPLAY 0.617021 (-5260 4035);
PAINT ORANGE (-5260 4035);
FORCEPROP 2 LASTPIN (-4150 4075) $PN 6
J 0
(-4140 4085);
DISPLAY 0.617021 (-4140 4085);
PAINT ORANGE (-4140 4085);
FORCEPROP 2 LASTPIN (-4150 4125) $PN 5
J 0
(-4140 4135);
DISPLAY 0.617021 (-4140 4135);
PAINT ORANGE (-4140 4135);
FORCEPROP 1 LAST LOCATION U7F1
J 0
(-5025 4375);
DISPLAY 0.617021 (-5025 4375);
PAINT AQUA (-5025 4375);
FORCEPROP 2 LASTPIN (-5250 4175) $PN 2
J 2
(-5260 4185);
DISPLAY 0.617021 (-5260 4185);
PAINT ORANGE (-5260 4185);
FORCEPROP 2 LASTPIN (-4150 4025) $PN 11
J 0
(-4140 4035);
DISPLAY 0.617021 (-4140 4035);
PAINT ORANGE (-4140 4035);
FORCEPROP 2 LASTPIN (-4150 3975) $PN 12
J 0
(-4140 3985);
DISPLAY 0.617021 (-4140 3985);
PAINT ORANGE (-4140 3985);
FORCEPROP 2 LASTPIN (-4150 3925) $PN 13
J 0
(-4140 3935);
DISPLAY 0.617021 (-4140 3935);
PAINT ORANGE (-4140 3935);
FORCEPROP 2 LASTPIN (-4150 3875) $PN 14
J 0
(-4140 3885);
DISPLAY 0.617021 (-4140 3885);
PAINT ORANGE (-4140 3885);
FORCEPROP 2 LASTPIN (-4150 3725) $PN 10
J 0
(-4140 3735);
DISPLAY 0.617021 (-4140 3735);
PAINT ORANGE (-4140 3735);
FORCEPROP 2 LASTPIN (-5250 3975) $PN 8
J 2
(-5260 3985);
DISPLAY 0.617021 (-5260 3985);
PAINT ORANGE (-5260 3985);
FORCEPROP 2 LASTPIN (-5250 3925) $PN 15
J 2
(-5260 3935);
DISPLAY 0.617021 (-5260 3935);
PAINT ORANGE (-5260 3935);
FORCEPROP 2 LASTPIN (-5250 3725) $PN 7
J 2
(-5260 3735);
DISPLAY 0.617021 (-5260 3735);
PAINT ORANGE (-5260 3735);
FORCEPROP 2 LASTPIN (-5250 3675) $PN 3
J 2
(-5260 3685);
DISPLAY 0.617021 (-5260 3685);
PAINT ORANGE (-5260 3685);
FORCEPROP 2 LASTPIN (-5250 3825) $PN 16
J 2
(-5260 3835);
DISPLAY 0.617021 (-5260 3835);
PAINT ORANGE (-5260 3835);
FORCEPROP 2 LASTPIN (-4150 4175) $PN 4
J 0
(-4140 4185);
DISPLAY 0.617021 (-4140 4185);
PAINT ORANGE (-4140 4185);
FORCEPROP 2 LAST SEC_TYPE XSOI
J 0
(-4700 4425);
DISPLAY 1.021277 (-4700 4425);
PAINT ORANGE (-4700 4425);
DISPLAY INVISIBLE (-4700 4425);
FORCEPROP 2 LAST SEC 1
J 0
(-4700 4425);
DISPLAY 0.680851 (-4700 4425);
PAINT MONO (-4700 4425);
DISPLAY INVISIBLE (-4700 4425);
FORCEPROP 1 LAST PATH I146
J 0
(-4700 4375);
PAINT GREEN (-4700 4375);
DISPLAY INVISIBLE (-4700 4375);
FORCEPROP 2 LAST ROOM SB_SPI
J 0
(-5200 4425);
DISPLAY 1.021277 (-5200 4425);
PAINT ORANGE (-5200 4425);
DISPLAY INVISIBLE (-5200 4425);
FORCEPROP 2 LAST CDS_LOCATION U7F1
J 0
(-5025 4375);
DISPLAY 0.617021 (-5025 4375);
PAINT AQUA (-5025 4375);
DISPLAY INVISIBLE (-5025 4375);
FORCEPROP 2 LAST BOM_COST MIO_BIOS_MEM
J 0
(-5200 4475);
DISPLAY 1.021277 (-5200 4475);
PAINT ORANGE (-5200 4475);
DISPLAY INVISIBLE (-5200 4475);
FORCEPROP 1 LAST PACK_TYPE XSOI
J 0
(-5200 4475);
PAINT SKYBLUE (-5200 4475);
DISPLAY INVISIBLE (-5200 4475);
FORCEPROP 2 LAST CDS_LIB mstr_memory
J 0
(-4700 3975);
PAINT MONO (-4700 3975);
DISPLAY INVISIBLE (-4700 3975);
FORCEADD RES..2
R 2
(-5875 2325);
FORCEPROP 1 LASTPIN (-5875 2225) $PN 2
J 2
(-5880 2235);
DISPLAY 0.617021 (-5880 2235);
PAINT ORANGE (-5880 2235);
FORCEPROP 1 LAST VALUE 4.75K
J 2
(-5920 2400);
DISPLAY 0.617021 (-5920 2400);
PAINT SKYBLUE (-5920 2400);
FORCEPROP 1 LAST LOCATION R3T3
J 2
(-5920 2450);
DISPLAY 0.617021 (-5920 2450);
PAINT AQUA (-5920 2450);
FORCEPROP 1 LASTPIN (-5875 2425) $PN 1
J 2
(-5880 2387);
DISPLAY 0.617021 (-5880 2387);
PAINT ORANGE (-5880 2387);
FORCEPROP 1 LAST TOLERANCE 1%
J 2
(-5920 2300);
DISPLAY 0.617021 (-5920 2300);
PAINT SKYBLUE (-5920 2300);
FORCEPROP 1 LAST MATERIAL EMPTY
J 2
(-5915 2350);
DISPLAY 0.617021 (-5915 2350);
PAINT RED (-5915 2350);
FORCEPROP 0 LAST GROUP NI_BIOS_ROM2
J 0
(-6075 2050);
DISPLAY 0.638298 (-6075 2050);
PAINT BROWN (-6075 2050);
DISPLAY BOTH (-6075 2050);
FORCEPROP 1 LAST PACK_TYPE 0402
J 2
(-5915 2150);
DISPLAY 0.617021 (-5915 2150);
PAINT SKYBLUE (-5915 2150);
FORCEPROP 1 LAST PART_NUMBER G21796-072
J 2
(-5915 2200);
DISPLAY 0.617021 (-5915 2200);
PAINT BLUE (-5915 2200);
FORCEPROP 1 LAST WATTAGE 1/16W
J 2
(-5915 2250);
DISPLAY 0.617021 (-5915 2250);
PAINT SKYBLUE (-5915 2250);
FORCEPROP 2 LAST CDS_LOCATION R3T3
J 2
(-5920 2450);
DISPLAY 0.617021 (-5920 2450);
PAINT AQUA (-5920 2450);
DISPLAY INVISIBLE (-5920 2450);
FORCEPROP 1 LAST PATH I150
J 2
(-5925 2500);
DISPLAY 0.978723 (-5925 2500);
PAINT WHITE (-5925 2500);
DISPLAY INVISIBLE (-5925 2500);
FORCEPROP 2 LAST ROOM SB_SPI
J 0
(-5900 2500);
DISPLAY 1.021277 (-5900 2500);
PAINT ORANGE (-5900 2500);
DISPLAY INVISIBLE (-5900 2500);
FORCEPROP 2 LAST CDS_LIB mstr_discrete
J 0
(-5875 2325);
PAINT ORANGE (-5875 2325);
DISPLAY INVISIBLE (-5875 2325);
FORCEPROP 2 LAST NO_XNET_CONNECTION 1
J 0
(-5925 2550);
PAINT MONO (-5925 2550);
DISPLAY INVISIBLE (-5925 2550);
FORCEPROP 2 LAST SEC 1
J 0
(-5925 2550);
DISPLAY 0.680851 (-5925 2550);
PAINT MONO (-5925 2550);
DISPLAY INVISIBLE (-5925 2550);
FORCEPROP 2 LAST BOM_COST MIO_BIOS_MEM
J 0
(-5900 2550);
DISPLAY 1.021277 (-5900 2550);
PAINT ORANGE (-5900 2550);
DISPLAY INVISIBLE (-5900 2550);
FORCEPROP 2 LAST SEC_TYPE 0402
J 0
(-5925 2550);
DISPLAY 1.021277 (-5925 2550);
PAINT ORANGE (-5925 2550);
DISPLAY INVISIBLE (-5925 2550);
FORCEADD P3V3_STBY..1
(-6375 2725);
FORCEPROP 3 LASTPIN (-6375 2675) SIG_NAME P3V3_STBY\g
J 0
(-6365 2685);
DISPLAY 0.659574 (-6365 2685);
PAINT MONO (-6365 2685);
DISPLAY INVISIBLE (-6365 2685);
FORCEPROP 1 LAST HDL_POWER P3V3_STBY
J 0
(-6675 2600);
DISPLAY 0.872340 (-6675 2600);
PAINT ORANGE (-6675 2600);
DISPLAY INVISIBLE (-6675 2600);
FORCEPROP 1 LAST PATH I151
J 0
(-6330 2727);
DISPLAY 0.340426 (-6330 2727);
PAINT GREEN (-6330 2727);
DISPLAY INVISIBLE (-6330 2727);
FORCEPROP 1 LAST BODY_TYPE PLUMBING
J 0
(-6420 2682);
DISPLAY 0.340426 (-6420 2682);
PAINT GREEN (-6420 2682);
DISPLAY INVISIBLE (-6420 2682);
FORCEPROP 2 LAST CDS_LIB mstr_symbols
J 0
(-6375 2725);
PAINT ORANGE (-6375 2725);
DISPLAY INVISIBLE (-6375 2725);
FORCEPROP 1 LAST SIZE 1B
J 0
(-6330 2747);
DISPLAY 0.340426 (-6330 2747);
PAINT GREEN (-6330 2747);
DISPLAY INVISIBLE (-6330 2747);
FORCEPROP 1 LAST VOLTAGE 3.3V
J 0
(-6420 2682);
DISPLAY 0.340426 (-6420 2682);
PAINT SKYBLUE (-6420 2682);
DISPLAY INVISIBLE (-6420 2682);
FORCEADD RES..2
R 2
(-6175 2325);
FORCEPROP 1 LAST WATTAGE 1/16W
J 2
(-6215 2250);
DISPLAY 0.617021 (-6215 2250);
PAINT SKYBLUE (-6215 2250);
FORCEPROP 1 LAST PART_NUMBER G21796-072
J 2
(-6215 2200);
DISPLAY 0.617021 (-6215 2200);
PAINT BLUE (-6215 2200);
FORCEPROP 1 LAST TOLERANCE 1%
J 2
(-6220 2300);
DISPLAY 0.617021 (-6220 2300);
PAINT SKYBLUE (-6220 2300);
FORCEPROP 1 LAST MATERIAL CHIP
J 2
(-6215 2350);
DISPLAY 0.617021 (-6215 2350);
PAINT SKYBLUE (-6215 2350);
FORCEPROP 1 LAST VALUE 4.75K
J 2
(-6220 2400);
DISPLAY 0.617021 (-6220 2400);
PAINT SKYBLUE (-6220 2400);
FORCEPROP 1 LAST LOCATION R3T5
J 2
(-6220 2450);
DISPLAY 0.617021 (-6220 2450);
PAINT AQUA (-6220 2450);
FORCEPROP 1 LASTPIN (-6175 2425) $PN 1
J 2
(-6180 2387);
DISPLAY 0.617021 (-6180 2387);
PAINT ORANGE (-6180 2387);
FORCEPROP 1 LASTPIN (-6175 2225) $PN 2
J 2
(-6180 2235);
DISPLAY 0.617021 (-6180 2235);
PAINT ORANGE (-6180 2235);
FORCEPROP 1 LAST PACK_TYPE 0402
J 2
(-6215 2150);
DISPLAY 0.617021 (-6215 2150);
PAINT SKYBLUE (-6215 2150);
FORCEPROP 0 LAST GROUP NI_BIOS_ROM2
J 0
(-6475 2100);
DISPLAY 0.638298 (-6475 2100);
PAINT BROWN (-6475 2100);
DISPLAY BOTH (-6475 2100);
FORCEPROP 2 LAST CDS_LIB mstr_discrete
J 0
(-6175 2325);
PAINT ORANGE (-6175 2325);
DISPLAY INVISIBLE (-6175 2325);
FORCEPROP 2 LAST ROOM SB_SPI
J 0
(-6200 2500);
DISPLAY 1.021277 (-6200 2500);
PAINT ORANGE (-6200 2500);
DISPLAY INVISIBLE (-6200 2500);
FORCEPROP 1 LAST PATH I152
J 2
(-6225 2500);
DISPLAY 0.978723 (-6225 2500);
PAINT WHITE (-6225 2500);
DISPLAY INVISIBLE (-6225 2500);
FORCEPROP 2 LAST CDS_LOCATION R3T5
J 2
(-6220 2450);
DISPLAY 0.617021 (-6220 2450);
PAINT AQUA (-6220 2450);
DISPLAY INVISIBLE (-6220 2450);
FORCEPROP 2 LAST NO_XNET_CONNECTION 1
J 0
(-6225 2550);
PAINT MONO (-6225 2550);
DISPLAY INVISIBLE (-6225 2550);
FORCEPROP 2 LAST SEC 1
J 0
(-6225 2550);
DISPLAY 0.680851 (-6225 2550);
PAINT MONO (-6225 2550);
DISPLAY INVISIBLE (-6225 2550);
FORCEPROP 2 LAST BOM_COST MIO_BIOS_MEM
J 0
(-6200 2550);
DISPLAY 1.021277 (-6200 2550);
PAINT ORANGE (-6200 2550);
DISPLAY INVISIBLE (-6200 2550);
FORCEPROP 2 LAST SEC_TYPE 0402
J 0
(-6225 2550);
DISPLAY 1.021277 (-6225 2550);
PAINT ORANGE (-6225 2550);
DISPLAY INVISIBLE (-6225 2550);
FORCEADD OFFPAGE..1
(-7100 1525);
FORCEPROP 2 LAST $XR0 153 
J 0
(-7352 1525);
DISPLAY 0.638298 (-7352 1525);
PAINT MONO (-7352 1525);
FORCEPROP 2 LAST PATH I153
J 0
(-7350 1575);
DISPLAY 1.021277 (-7350 1575);
PAINT ORANGE (-7350 1575);
DISPLAY INVISIBLE (-7350 1575);
FORCEPROP 1 LAST OFFPAGE TRUE
J 0
(-6775 1400);
DISPLAY 0.872340 (-6775 1400);
PAINT GREEN (-6775 1400);
DISPLAY INVISIBLE (-6775 1400);
FORCEPROP 1 LAST COMMENT_BODY TRUE
J 0
(-6975 1425);
DISPLAY 0.872340 (-6975 1425);
PAINT GREEN (-6975 1425);
DISPLAY INVISIBLE (-6975 1425);
FORCEPROP 2 LAST CDS_LIB mstr_standard
J 0
(-7100 1525);
PAINT ORANGE (-7100 1525);
DISPLAY INVISIBLE (-7100 1525);
FORCEADD RES..1
(-6275 1675);
FORCEPROP 1 LAST TOLERANCE 1%
J 0
(-6500 1625);
DISPLAY 0.638298 (-6500 1625);
PAINT SKYBLUE (-6500 1625);
FORCEPROP 1 LASTPIN (-6175 1675) $PN 2
J 0
(-6213 1687);
DISPLAY 0.617021 (-6213 1687);
PAINT MONO (-6213 1687);
FORCEPROP 1 LASTPIN (-6375 1675) $PN 1
J 0
(-6363 1687);
DISPLAY 0.617021 (-6363 1687);
PAINT MONO (-6363 1687);
FORCEPROP 1 LAST LOCATION R3T2
J 0
(-6507 1682);
DISPLAY 0.617021 (-6507 1682);
PAINT AQUA (-6507 1682);
FORCEPROP 1 LAST WATTAGE 1/16W
J 0
(-6400 1625);
DISPLAY 0.638298 (-6400 1625);
PAINT SKYBLUE (-6400 1625);
FORCEPROP 0 LAST GROUP NI_BIOS_ROM2
J 0
(-6500 1575);
DISPLAY 0.638298 (-6500 1575);
PAINT BROWN (-6500 1575);
DISPLAY BOTH (-6500 1575);
FORCEPROP 1 LAST MATERIAL CHIP
J 0
(-6250 1625);
DISPLAY 0.638298 (-6250 1625);
PAINT SKYBLUE (-6250 1625);
FORCEPROP 1 LAST VALUE 33.2
J 0
(-6150 1682);
DISPLAY 0.617021 (-6150 1682);
PAINT SKYBLUE (-6150 1682);
FORCEPROP 1 LAST PART_NUMBER G21796-074
J 0
(-6100 1625);
DISPLAY 0.638298 (-6100 1625);
PAINT BLUE (-6100 1625);
FORCEPROP 1 LAST PACK_TYPE 0402
J 0
(-5850 1625);
DISPLAY 0.638298 (-5850 1625);
PAINT SKYBLUE (-5850 1625);
FORCEPROP 2 LAST BOM_COST MIO_BIOS_MEM
J 0
(-6050 1775);
DISPLAY 1.021277 (-6050 1775);
PAINT ORANGE (-6050 1775);
DISPLAY INVISIBLE (-6050 1775);
FORCEPROP 2 LAST ROOM SB_SPI
J 0
(-6050 1725);
DISPLAY 1.021277 (-6050 1725);
PAINT ORANGE (-6050 1725);
DISPLAY INVISIBLE (-6050 1725);
FORCEPROP 2 LAST CDS_LOCATION R3T2
J 0
(-6182 1632);
DISPLAY 0.617021 (-6182 1632);
PAINT AQUA (-6182 1632);
DISPLAY INVISIBLE (-6182 1632);
FORCEPROP 2 LAST SEC 1
J 0
(-6325 1900);
DISPLAY 0.680851 (-6325 1900);
PAINT MONO (-6325 1900);
DISPLAY INVISIBLE (-6325 1900);
FORCEPROP 2 LAST SEC_TYPE 0402
J 0
(-6325 1900);
DISPLAY 1.021277 (-6325 1900);
PAINT ORANGE (-6325 1900);
DISPLAY INVISIBLE (-6325 1900);
FORCEPROP 1 LAST PATH I155
J 0
(-6325 1825);
DISPLAY 0.978723 (-6325 1825);
PAINT WHITE (-6325 1825);
DISPLAY INVISIBLE (-6325 1825);
FORCEPROP 2 LAST CDS_LIB mstr_discrete
J 1
(-6275 1675);
PAINT ORANGE (-6275 1675);
DISPLAY INVISIBLE (-6275 1675);
FORCEADD RES..1
(-6425 1425);
FORCEPROP 1 LAST LOCATION R3U1
J 0
(-6725 1450);
DISPLAY 0.617021 (-6725 1450);
PAINT AQUA (-6725 1450);
FORCEPROP 1 LAST VALUE 33.2
J 2
(-6500 1350);
DISPLAY 0.617021 (-6500 1350);
PAINT SKYBLUE (-6500 1350);
FORCEPROP 1 LAST WATTAGE 1/16W
J 2
(-6625 1350);
DISPLAY 0.617021 (-6625 1350);
PAINT SKYBLUE (-6625 1350);
FORCEPROP 1 LASTPIN (-6325 1425) $PN 2
J 0
(-6363 1437);
DISPLAY 0.787234 (-6363 1437);
PAINT ORANGE (-6363 1437);
FORCEPROP 1 LAST TOLERANCE 1%
J 0
(-6400 1350);
DISPLAY 0.617021 (-6400 1350);
PAINT SKYBLUE (-6400 1350);
FORCEPROP 1 LASTPIN (-6525 1425) $PN 1
J 0
(-6513 1437);
DISPLAY 0.787234 (-6513 1437);
PAINT ORANGE (-6513 1437);
FORCEPROP 1 LAST PACK_TYPE 0402
J 0
(-6100 1350);
DISPLAY 0.617021 (-6100 1350);
PAINT SKYBLUE (-6100 1350);
FORCEPROP 1 LAST PART_NUMBER G21796-074
J 0
(-6275 1450);
DISPLAY 0.617021 (-6275 1450);
PAINT BLUE (-6275 1450);
FORCEPROP 1 LAST MATERIAL CHIP
J 0
(-6275 1350);
DISPLAY 0.617021 (-6275 1350);
PAINT SKYBLUE (-6275 1350);
FORCEPROP 0 LAST GROUP NI_BIOS_ROM2
J 0
(-6750 1300);
DISPLAY 0.638298 (-6750 1300);
PAINT BROWN (-6750 1300);
DISPLAY BOTH (-6750 1300);
FORCEPROP 2 LAST SEC 1
J 0
(-6475 1625);
PAINT MONO (-6475 1625);
DISPLAY INVISIBLE (-6475 1625);
FORCEPROP 2 LAST SEC_TYPE 0402
J 0
(-6475 1625);
DISPLAY 1.021277 (-6475 1625);
PAINT ORANGE (-6475 1625);
DISPLAY INVISIBLE (-6475 1625);
FORCEPROP 2 LAST NO_XNET_CONNECTION 1
J 0
(-6475 1625);
PAINT MONO (-6475 1625);
DISPLAY INVISIBLE (-6475 1625);
FORCEPROP 1 LAST PATH I156
J 0
(-6475 1575);
DISPLAY 0.978723 (-6475 1575);
PAINT WHITE (-6475 1575);
DISPLAY INVISIBLE (-6475 1575);
FORCEPROP 2 LAST BOM_COST MIO_BIOS_MEM
J 0
(-6475 1575);
DISPLAY 1.021277 (-6475 1575);
PAINT ORANGE (-6475 1575);
DISPLAY INVISIBLE (-6475 1575);
FORCEPROP 2 LAST ROOM SB_SPI
J 0
(-6475 1525);
DISPLAY 1.021277 (-6475 1525);
PAINT ORANGE (-6475 1525);
DISPLAY INVISIBLE (-6475 1525);
FORCEPROP 2 LAST CDS_LOCATION R3U1
J 0
(-6475 1475);
DISPLAY 0.617021 (-6475 1475);
PAINT AQUA (-6475 1475);
DISPLAY INVISIBLE (-6475 1475);
FORCEPROP 2 LAST CDS_LIB mstr_discrete
J 0
(-6425 1425);
PAINT ORANGE (-6425 1425);
DISPLAY INVISIBLE (-6425 1425);
FORCEADD RES..1
(-6425 1200);
FORCEPROP 1 LAST LOCATION R3T1
J 0
(-6725 1225);
DISPLAY 0.617021 (-6725 1225);
PAINT AQUA (-6725 1225);
FORCEPROP 1 LASTPIN (-6325 1200) $PN 2
J 0
(-6363 1212);
DISPLAY 0.787234 (-6363 1212);
PAINT ORANGE (-6363 1212);
FORCEPROP 1 LAST WATTAGE 1/16W
J 2
(-6625 1125);
DISPLAY 0.617021 (-6625 1125);
PAINT SKYBLUE (-6625 1125);
FORCEPROP 1 LAST VALUE 33.2
J 2
(-6500 1125);
DISPLAY 0.617021 (-6500 1125);
PAINT SKYBLUE (-6500 1125);
FORCEPROP 1 LASTPIN (-6525 1200) $PN 1
J 0
(-6513 1212);
DISPLAY 0.787234 (-6513 1212);
PAINT ORANGE (-6513 1212);
FORCEPROP 1 LAST PACK_TYPE 0402
J 0
(-6100 1125);
DISPLAY 0.617021 (-6100 1125);
PAINT SKYBLUE (-6100 1125);
FORCEPROP 1 LAST PART_NUMBER G21796-074
J 0
(-6275 1225);
DISPLAY 0.617021 (-6275 1225);
PAINT BLUE (-6275 1225);
FORCEPROP 1 LAST MATERIAL CHIP
J 0
(-6275 1125);
DISPLAY 0.617021 (-6275 1125);
PAINT SKYBLUE (-6275 1125);
FORCEPROP 0 LAST GROUP NI_BIOS_ROM2
J 0
(-6750 1075);
DISPLAY 0.638298 (-6750 1075);
PAINT BROWN (-6750 1075);
DISPLAY BOTH (-6750 1075);
FORCEPROP 1 LAST TOLERANCE 1%
J 0
(-6400 1125);
DISPLAY 0.617021 (-6400 1125);
PAINT SKYBLUE (-6400 1125);
FORCEPROP 2 LAST CDS_LIB mstr_discrete
J 0
(-6425 1200);
PAINT ORANGE (-6425 1200);
DISPLAY INVISIBLE (-6425 1200);
FORCEPROP 1 LAST PATH I157
J 0
(-6475 1350);
DISPLAY 0.978723 (-6475 1350);
PAINT WHITE (-6475 1350);
DISPLAY INVISIBLE (-6475 1350);
FORCEPROP 2 LAST ROOM SB_SPI
J 0
(-6475 1300);
DISPLAY 1.021277 (-6475 1300);
PAINT ORANGE (-6475 1300);
DISPLAY INVISIBLE (-6475 1300);
FORCEPROP 2 LAST BOM_COST MIO_BIOS_MEM
J 0
(-6475 1350);
DISPLAY 1.021277 (-6475 1350);
PAINT ORANGE (-6475 1350);
DISPLAY INVISIBLE (-6475 1350);
FORCEPROP 2 LAST NO_XNET_CONNECTION 1
J 0
(-6475 1400);
PAINT MONO (-6475 1400);
DISPLAY INVISIBLE (-6475 1400);
FORCEPROP 2 LAST CDS_LOCATION R3T1
J 0
(-6475 1250);
DISPLAY 0.617021 (-6475 1250);
PAINT AQUA (-6475 1250);
DISPLAY INVISIBLE (-6475 1250);
FORCEPROP 2 LAST SEC 1
J 0
(-6475 1400);
PAINT MONO (-6475 1400);
DISPLAY INVISIBLE (-6475 1400);
FORCEPROP 2 LAST SEC_TYPE 0402
J 0
(-6475 1400);
DISPLAY 1.021277 (-6475 1400);
PAINT ORANGE (-6475 1400);
DISPLAY INVISIBLE (-6475 1400);
FORCEADD OFFPAGE..5
(-7100 1675);
FORCEPROP 2 LAST $XR1 154 
J 0
(-7475 1675);
DISPLAY 0.638298 (-7475 1675);
PAINT MONO (-7475 1675);
FORCEPROP 2 LAST $XR0 153 
J 0
(-7355 1675);
DISPLAY 0.638298 (-7355 1675);
PAINT MONO (-7355 1675);
FORCEPROP 1 LAST OFFPAGE TRUE
J 0
(-6775 1550);
PAINT GREEN (-6775 1550);
DISPLAY INVISIBLE (-6775 1550);
FORCEPROP 1 LAST COMMENT_BODY TRUE
J 0
(-7000 1600);
DISPLAY 1.170213 (-7000 1600);
PAINT GREEN (-7000 1600);
DISPLAY INVISIBLE (-7000 1600);
FORCEPROP 2 LAST CDS_LIB mstr_standard
J 1
(-7100 1675);
PAINT ORANGE (-7100 1675);
DISPLAY INVISIBLE (-7100 1675);
FORCEPROP 2 LAST PATH I158
J 0
(-7375 1725);
DISPLAY 1.021277 (-7375 1725);
PAINT ORANGE (-7375 1725);
DISPLAY INVISIBLE (-7375 1725);
FORCEADD OFFPAGE..1
(-7100 1575);
FORCEPROP 2 LAST $XR0 153 
J 0
(-7352 1575);
DISPLAY 0.638298 (-7352 1575);
PAINT MONO (-7352 1575);
FORCEPROP 1 LAST OFFPAGE TRUE
J 0
(-6775 1450);
DISPLAY 0.872340 (-6775 1450);
PAINT GREEN (-6775 1450);
DISPLAY INVISIBLE (-6775 1450);
FORCEPROP 1 LAST COMMENT_BODY TRUE
J 0
(-6975 1475);
DISPLAY 0.872340 (-6975 1475);
PAINT GREEN (-6975 1475);
DISPLAY INVISIBLE (-6975 1475);
FORCEPROP 2 LAST CDS_LIB mstr_standard
J 0
(-7100 1575);
PAINT ORANGE (-7100 1575);
DISPLAY INVISIBLE (-7100 1575);
FORCEPROP 2 LAST PATH I159
J 0
(-7350 1625);
DISPLAY 1.021277 (-7350 1625);
PAINT ORANGE (-7350 1625);
DISPLAY INVISIBLE (-7350 1625);
FORCEADD OFFPAGE..1
(-7100 1875);
FORCEPROP 2 LAST $XR0 154 
J 0
(-7352 1875);
DISPLAY 0.638298 (-7352 1875);
PAINT MONO (-7352 1875);
FORCEPROP 2 LAST PATH I161
J 0
(-7350 1925);
DISPLAY 1.021277 (-7350 1925);
PAINT ORANGE (-7350 1925);
DISPLAY INVISIBLE (-7350 1925);
FORCEPROP 1 LAST COMMENT_BODY TRUE
J 0
(-6975 1775);
DISPLAY 0.978723 (-6975 1775);
PAINT PEACH (-6975 1775);
DISPLAY INVISIBLE (-6975 1775);
FORCEPROP 1 LAST OFFPAGE TRUE
J 0
(-6775 1750);
PAINT GREEN (-6775 1750);
DISPLAY INVISIBLE (-6775 1750);
FORCEPROP 2 LAST CDS_LIB mstr_standard
J 0
(-7100 1875);
DISPLAY 1.531915 (-7100 1875);
PAINT ORANGE (-7100 1875);
DISPLAY INVISIBLE (-7100 1875);
FORCEADD OFFPAGE..1
(-7100 1825);
FORCEPROP 2 LAST $XR1 153 
J 0
(-7472 1825);
DISPLAY 0.638298 (-7472 1825);
PAINT MONO (-7472 1825);
FORCEPROP 2 LAST $XR0 154 
J 0
(-7352 1825);
DISPLAY 0.638298 (-7352 1825);
PAINT MONO (-7352 1825);
FORCEPROP 1 LAST OFFPAGE TRUE
J 0
(-6775 1700);
PAINT GREEN (-6775 1700);
DISPLAY INVISIBLE (-6775 1700);
FORCEPROP 1 LAST COMMENT_BODY TRUE
J 0
(-6975 1725);
DISPLAY 0.978723 (-6975 1725);
PAINT PEACH (-6975 1725);
DISPLAY INVISIBLE (-6975 1725);
FORCEPROP 2 LAST CDS_LIB mstr_standard
J 0
(-7100 1825);
DISPLAY 1.531915 (-7100 1825);
PAINT ORANGE (-7100 1825);
DISPLAY INVISIBLE (-7100 1825);
FORCEPROP 2 LAST PATH I162
J 0
(-7350 1875);
DISPLAY 1.021277 (-7350 1875);
PAINT ORANGE (-7350 1875);
DISPLAY INVISIBLE (-7350 1875);
FORCEADD OFFPAGE..1
(-7350 1425);
FORCEPROP 2 LAST $XR1 153 
J 0
(-7722 1425);
DISPLAY 0.638298 (-7722 1425);
PAINT MONO (-7722 1425);
FORCEPROP 2 LAST $XR0 154 
J 0
(-7602 1425);
DISPLAY 0.638298 (-7602 1425);
PAINT MONO (-7602 1425);
FORCEPROP 1 LAST COMMENT_BODY TRUE
J 0
(-7225 1325);
DISPLAY 0.872340 (-7225 1325);
PAINT GREEN (-7225 1325);
DISPLAY INVISIBLE (-7225 1325);
FORCEPROP 2 LAST CDS_LIB mstr_standard
J 0
(-7350 1425);
PAINT ORANGE (-7350 1425);
DISPLAY INVISIBLE (-7350 1425);
FORCEPROP 2 LAST PATH I163
J 0
(-7600 1475);
DISPLAY 1.021277 (-7600 1475);
PAINT ORANGE (-7600 1475);
DISPLAY INVISIBLE (-7600 1475);
FORCEPROP 1 LAST OFFPAGE TRUE
J 0
(-7025 1300);
DISPLAY 0.872340 (-7025 1300);
PAINT GREEN (-7025 1300);
DISPLAY INVISIBLE (-7025 1300);
FORCEADD OFFPAGE..1
(-7300 1200);
FORCEPROP 2 LAST $XR1 153 
J 0
(-7672 1200);
DISPLAY 0.638298 (-7672 1200);
PAINT MONO (-7672 1200);
FORCEPROP 2 LAST $XR0 154 
J 0
(-7552 1200);
DISPLAY 0.638298 (-7552 1200);
PAINT MONO (-7552 1200);
FORCEPROP 2 LAST PATH I164
J 0
(-7550 1250);
DISPLAY 1.021277 (-7550 1250);
PAINT ORANGE (-7550 1250);
DISPLAY INVISIBLE (-7550 1250);
FORCEPROP 1 LAST COMMENT_BODY TRUE
J 0
(-7175 1100);
DISPLAY 0.872340 (-7175 1100);
PAINT GREEN (-7175 1100);
DISPLAY INVISIBLE (-7175 1100);
FORCEPROP 2 LAST CDS_LIB mstr_standard
J 0
(-7300 1200);
PAINT ORANGE (-7300 1200);
DISPLAY INVISIBLE (-7300 1200);
FORCEPROP 1 LAST OFFPAGE TRUE
J 0
(-6975 1075);
DISPLAY 0.872340 (-6975 1075);
PAINT GREEN (-6975 1075);
DISPLAY INVISIBLE (-6975 1075);
FORCEADD RES..1
(-6550 3825);
FORCEPROP 1 LAST MATERIAL CHIP
J 0
(-6400 3825);
DISPLAY 0.617021 (-6400 3825);
PAINT SKYBLUE (-6400 3825);
FORCEPROP 1 LAST WATTAGE 1/16W
J 0
(-6450 3875);
DISPLAY 0.617021 (-6450 3875);
PAINT SKYBLUE (-6450 3875);
FORCEPROP 1 LASTPIN (-6650 3825) $PN 1
J 0
(-6638 3837);
DISPLAY 0.617021 (-6638 3837);
PAINT MONO (-6638 3837);
FORCEPROP 1 LAST LOCATION R8F8
J 0
(-6775 3875);
DISPLAY 0.617021 (-6775 3875);
PAINT AQUA (-6775 3875);
FORCEPROP 1 LASTPIN (-6450 3825) $PN 2
J 0
(-6488 3837);
DISPLAY 0.617021 (-6488 3837);
PAINT MONO (-6488 3837);
FORCEPROP 1 LAST TOLERANCE 1%
J 0
(-6550 3875);
DISPLAY 0.617021 (-6550 3875);
PAINT SKYBLUE (-6550 3875);
FORCEPROP 1 LAST VALUE 33.2
J 0
(-6650 3875);
DISPLAY 0.617021 (-6650 3875);
PAINT SKYBLUE (-6650 3875);
FORCEPROP 1 LAST PACK_TYPE 0402
J 0
(-6200 3825);
DISPLAY 0.617021 (-6200 3825);
PAINT SKYBLUE (-6200 3825);
FORCEPROP 1 LAST PART_NUMBER G21796-074
J 0
(-6300 3875);
DISPLAY 0.617021 (-6300 3875);
PAINT BLUE (-6300 3875);
FORCEPROP 2 LAST CDS_LIB mstr_discrete
J 0
(-6550 3825);
PAINT ORANGE (-6550 3825);
DISPLAY INVISIBLE (-6550 3825);
FORCEPROP 2 LAST ROOM MIO_BIOS_MEM
J 0
(-6600 3965);
DISPLAY 0.787234 (-6600 3965);
PAINT SKYBLUE (-6600 3965);
DISPLAY INVISIBLE (-6600 3965);
FORCEPROP 1 LAST PATH I166
J 0
(-6600 3975);
DISPLAY 0.978723 (-6600 3975);
PAINT WHITE (-6600 3975);
DISPLAY INVISIBLE (-6600 3975);
FORCEPROP 2 LAST CDS_LOCATION R8F8
J 0
(-6600 3850);
DISPLAY 0.617021 (-6600 3850);
PAINT AQUA (-6600 3850);
DISPLAY INVISIBLE (-6600 3850);
FORCEPROP 2 LAST $SEC 1
J 0
(-6600 4025);
DISPLAY 0.936170 (-6600 4025);
PAINT MONO (-6600 4025);
DISPLAY INVISIBLE (-6600 4025);
FORCEPROP 2 LAST CDS_SEC 1
J 0
(-6600 4025);
DISPLAY 1.404255 (-6600 4025);
PAINT ORANGE (-6600 4025);
DISPLAY INVISIBLE (-6600 4025);
FORCEADD RES..1
(-6275 1825);
FORCEPROP 1 LAST TOLERANCE 1%
J 0
(-6350 1875);
DISPLAY 0.617021 (-6350 1875);
PAINT SKYBLUE (-6350 1875);
FORCEPROP 1 LASTPIN (-6375 1825) $PN 1
J 0
(-6363 1837);
DISPLAY 0.787234 (-6363 1837);
PAINT ORANGE (-6363 1837);
FORCEPROP 1 LAST VALUE 33.2
J 0
(-6500 1875);
DISPLAY 0.617021 (-6500 1875);
PAINT SKYBLUE (-6500 1875);
FORCEPROP 1 LAST WATTAGE 1/16W
J 0
(-6250 1875);
DISPLAY 0.617021 (-6250 1875);
PAINT SKYBLUE (-6250 1875);
FORCEPROP 1 LASTPIN (-6175 1825) $PN 2
J 0
(-6213 1837);
DISPLAY 0.787234 (-6213 1837);
PAINT ORANGE (-6213 1837);
FORCEPROP 1 LAST LOCATION R8F7
J 0
(-6500 1825);
DISPLAY 0.617021 (-6500 1825);
PAINT AQUA (-6500 1825);
FORCEPROP 1 LAST PACK_TYPE 0402
J 0
(-5950 1875);
DISPLAY 0.617021 (-5950 1875);
PAINT SKYBLUE (-5950 1875);
FORCEPROP 1 LAST PART_NUMBER G21796-074
J 0
(-6150 1825);
DISPLAY 0.617021 (-6150 1825);
PAINT BLUE (-6150 1825);
FORCEPROP 1 LAST MATERIAL CHIP
J 0
(-6100 1875);
DISPLAY 0.617021 (-6100 1875);
PAINT SKYBLUE (-6100 1875);
FORCEPROP 0 LAST GROUP NI_BIOS_ROM2
J 0
(-6500 1925);
DISPLAY 0.638298 (-6500 1925);
PAINT BROWN (-6500 1925);
DISPLAY BOTH (-6500 1925);
FORCEPROP 2 LAST SEC_TYPE 0402
J 0
(-6325 2025);
DISPLAY 1.021277 (-6325 2025);
PAINT ORANGE (-6325 2025);
DISPLAY INVISIBLE (-6325 2025);
FORCEPROP 2 LAST SEC 1
J 0
(-6325 2025);
DISPLAY 0.680851 (-6325 2025);
PAINT MONO (-6325 2025);
DISPLAY INVISIBLE (-6325 2025);
FORCEPROP 2 LAST CDS_LOCATION R8F7
J 0
(-6325 1850);
DISPLAY 0.617021 (-6325 1850);
PAINT AQUA (-6325 1850);
DISPLAY INVISIBLE (-6325 1850);
FORCEPROP 2 LAST CDS_LIB mstr_discrete
J 0
(-6275 1825);
PAINT ORANGE (-6275 1825);
DISPLAY INVISIBLE (-6275 1825);
FORCEPROP 2 LAST ROOM MIO_BIOS_MEM
J 0
(-6325 1965);
DISPLAY 0.787234 (-6325 1965);
PAINT SKYBLUE (-6325 1965);
DISPLAY INVISIBLE (-6325 1965);
FORCEPROP 1 LAST PATH I167
J 0
(-6325 1975);
DISPLAY 0.978723 (-6325 1975);
PAINT WHITE (-6325 1975);
DISPLAY INVISIBLE (-6325 1975);
FORCEADD RES..2
(-1750 3925);
FORCEPROP 1 LAST VALUE 10.0K
J 0
(-1705 4000);
DISPLAY 0.617021 (-1705 4000);
PAINT SKYBLUE (-1705 4000);
FORCEPROP 1 LAST PACK_TYPE 0402
J 0
(-1710 3750);
DISPLAY 0.617021 (-1710 3750);
PAINT SKYBLUE (-1710 3750);
FORCEPROP 1 LASTPIN (-1750 3825) $PN 2
J 0
(-1745 3835);
DISPLAY 0.617021 (-1745 3835);
PAINT ORANGE (-1745 3835);
FORCEPROP 1 LASTPIN (-1750 4025) $PN 1
J 0
(-1745 3987);
DISPLAY 0.617021 (-1745 3987);
PAINT ORANGE (-1745 3987);
FORCEPROP 1 LAST WATTAGE 1/16W
J 0
(-1710 3900);
DISPLAY 0.617021 (-1710 3900);
PAINT SKYBLUE (-1710 3900);
FORCEPROP 1 LAST LOCATION R7F28
J 0
(-1705 4050);
DISPLAY 0.617021 (-1705 4050);
PAINT AQUA (-1705 4050);
FORCEPROP 1 LAST TOLERANCE 1%
J 0
(-1705 3950);
DISPLAY 0.617021 (-1705 3950);
PAINT SKYBLUE (-1705 3950);
FORCEPROP 1 LAST MATERIAL CHIP
J 0
(-1710 3850);
DISPLAY 0.617021 (-1710 3850);
PAINT SKYBLUE (-1710 3850);
FORCEPROP 1 LAST PART_NUMBER G21796-016
J 0
(-1710 3800);
DISPLAY 0.617021 (-1710 3800);
PAINT BLUE (-1710 3800);
FORCEPROP 2 LAST CDS_LIB mstr_discrete
J 0
(-1750 3925);
PAINT MONO (-1750 3925);
DISPLAY INVISIBLE (-1750 3925);
FORCEPROP 2 LAST CDS_LOCATION R7F28
J 0
(-1705 4050);
DISPLAY 0.617021 (-1705 4050);
PAINT AQUA (-1705 4050);
DISPLAY INVISIBLE (-1705 4050);
FORCEPROP 0 LAST BOM_COST MIO_BIOS_MEM
J 0
(-1700 4250);
DISPLAY 1.021277 (-1700 4250);
PAINT ORANGE (-1700 4250);
DISPLAY INVISIBLE (-1700 4250);
FORCEPROP 2 LAST SEC_TYPE 0402
J 0
(-1700 4150);
DISPLAY 1.021277 (-1700 4150);
PAINT ORANGE (-1700 4150);
DISPLAY INVISIBLE (-1700 4150);
FORCEPROP 0 LAST ROOM SB_SPI
J 0
(-1700 4150);
DISPLAY 1.021277 (-1700 4150);
PAINT ORANGE (-1700 4150);
DISPLAY INVISIBLE (-1700 4150);
FORCEPROP 1 LAST PATH I168
J 0
(-1700 4100);
DISPLAY 0.978723 (-1700 4100);
PAINT WHITE (-1700 4100);
DISPLAY INVISIBLE (-1700 4100);
FORCEPROP 2 LAST NO_XNET_CONNECTION 1
J 0
(-1700 4150);
PAINT MONO (-1700 4150);
DISPLAY INVISIBLE (-1700 4150);
FORCEPROP 2 LAST SEC 1
J 0
(-1700 4150);
DISPLAY 0.680851 (-1700 4150);
PAINT MONO (-1700 4150);
DISPLAY INVISIBLE (-1700 4150);
FORCEADD P3V3_STBY..1
(-1750 4175);
FORCEPROP 3 LASTPIN (-1750 4125) SIG_NAME P3V3_STBY\g
J 0
(-1740 4135);
DISPLAY 0.659574 (-1740 4135);
PAINT MONO (-1740 4135);
DISPLAY INVISIBLE (-1740 4135);
FORCEPROP 1 LAST HDL_POWER P3V3_STBY
J 0
(-2050 4050);
DISPLAY 0.872340 (-2050 4050);
PAINT ORANGE (-2050 4050);
DISPLAY INVISIBLE (-2050 4050);
FORCEPROP 1 LAST BODY_TYPE PLUMBING
J 0
(-1795 4132);
DISPLAY 0.340426 (-1795 4132);
PAINT GREEN (-1795 4132);
DISPLAY INVISIBLE (-1795 4132);
FORCEPROP 1 LAST VOLTAGE 3.3V
J 0
(-1795 4132);
DISPLAY 0.340426 (-1795 4132);
PAINT SKYBLUE (-1795 4132);
DISPLAY INVISIBLE (-1795 4132);
FORCEPROP 1 LAST SIZE 1B
J 0
(-1705 4197);
DISPLAY 0.340426 (-1705 4197);
PAINT GREEN (-1705 4197);
DISPLAY INVISIBLE (-1705 4197);
FORCEPROP 2 LAST CDS_LIB mstr_symbols
J 0
(-1750 4175);
PAINT MONO (-1750 4175);
DISPLAY INVISIBLE (-1750 4175);
FORCEPROP 1 LAST PATH I169
J 0
(-1705 4177);
DISPLAY 0.340426 (-1705 4177);
PAINT GREEN (-1705 4177);
DISPLAY INVISIBLE (-1705 4177);
FORCEADD RES..2
(-1750 3550);
FORCEPROP 1 LAST PART_NUMBER G21796-016
J 0
(-1710 3425);
DISPLAY 0.617021 (-1710 3425);
PAINT BLUE (-1710 3425);
FORCEPROP 1 LAST PACK_TYPE 0402
J 0
(-1710 3375);
DISPLAY 0.617021 (-1710 3375);
PAINT SKYBLUE (-1710 3375);
FORCEPROP 1 LASTPIN (-1750 3450) $PN 2
J 0
(-1745 3460);
DISPLAY 0.617021 (-1745 3460);
PAINT ORANGE (-1745 3460);
FORCEPROP 1 LAST WATTAGE 1/16W
J 0
(-1710 3525);
DISPLAY 0.617021 (-1710 3525);
PAINT SKYBLUE (-1710 3525);
FORCEPROP 1 LAST MATERIAL EMPTY
J 0
(-1710 3475);
DISPLAY 0.617021 (-1710 3475);
PAINT RED (-1710 3475);
FORCEPROP 1 LAST TOLERANCE 1%
J 0
(-1705 3575);
DISPLAY 0.617021 (-1705 3575);
PAINT SKYBLUE (-1705 3575);
FORCEPROP 1 LASTPIN (-1750 3650) $PN 1
J 0
(-1745 3612);
DISPLAY 0.617021 (-1745 3612);
PAINT ORANGE (-1745 3612);
FORCEPROP 1 LAST VALUE 10.0K
J 0
(-1705 3625);
DISPLAY 0.617021 (-1705 3625);
PAINT SKYBLUE (-1705 3625);
FORCEPROP 1 LAST LOCATION R7F30
J 0
(-1705 3675);
DISPLAY 0.617021 (-1705 3675);
PAINT AQUA (-1705 3675);
FORCEPROP 2 LAST CDS_LIB mstr_discrete
J 0
(-1750 3550);
PAINT MONO (-1750 3550);
DISPLAY INVISIBLE (-1750 3550);
FORCEPROP 2 LAST CDS_LOCATION R7F30
J 0
(-1705 3675);
DISPLAY 0.617021 (-1705 3675);
PAINT AQUA (-1705 3675);
DISPLAY INVISIBLE (-1705 3675);
FORCEPROP 0 LAST ROOM SB_SPI
J 0
(-1700 3775);
DISPLAY 1.021277 (-1700 3775);
PAINT ORANGE (-1700 3775);
DISPLAY INVISIBLE (-1700 3775);
FORCEPROP 1 LAST PATH I170
J 0
(-1700 3725);
DISPLAY 0.978723 (-1700 3725);
PAINT WHITE (-1700 3725);
DISPLAY INVISIBLE (-1700 3725);
FORCEPROP 2 LAST SEC 1
J 0
(-1700 3775);
DISPLAY 0.680851 (-1700 3775);
PAINT MONO (-1700 3775);
DISPLAY INVISIBLE (-1700 3775);
FORCEPROP 2 LAST SEC_TYPE 0402
J 0
(-1700 3775);
DISPLAY 1.021277 (-1700 3775);
PAINT ORANGE (-1700 3775);
DISPLAY INVISIBLE (-1700 3775);
FORCEPROP 0 LAST BOM_COST MIO_BIOS_MEM
J 0
(-1700 3875);
DISPLAY 1.021277 (-1700 3875);
PAINT ORANGE (-1700 3875);
DISPLAY INVISIBLE (-1700 3875);
FORCEADD OFFPAGE..2
(-650 3750);
FORCEPROP 2 LAST $XR0 153 
J 0
(-461 3750);
DISPLAY 0.638298 (-461 3750);
PAINT MONO (-461 3750);
FORCEPROP 1 LAST COMMENT_BODY TRUE
J 0
(-695 3655);
DISPLAY 0.872340 (-695 3655);
PAINT GREEN (-695 3655);
DISPLAY INVISIBLE (-695 3655);
FORCEPROP 2 LAST CDS_LIB mstr_standard
J 0
(-650 3750);
PAINT MONO (-650 3750);
DISPLAY INVISIBLE (-650 3750);
FORCEPROP 2 LAST PATH I171
J 0
(-475 3825);
DISPLAY 1.021277 (-475 3825);
PAINT ORANGE (-475 3825);
DISPLAY INVISIBLE (-475 3825);
FORCEPROP 1 LAST OFFPAGE TRUE
J 0
(-325 3625);
DISPLAY 0.872340 (-325 3625);
PAINT GREEN (-325 3625);
DISPLAY INVISIBLE (-325 3625);
FORCEADD GND..1
(-1750 3325);
FORCEPROP 3 LASTPIN (-1750 3375) SIG_NAME GND\g
J 0
(-1740 3385);
DISPLAY 0.659574 (-1740 3385);
PAINT MONO (-1740 3385);
DISPLAY INVISIBLE (-1740 3385);
FORCEPROP 1 LAST BODY_TYPE PLUMBING
J 0
(-1795 3282);
DISPLAY 0.340426 (-1795 3282);
PAINT GREEN (-1795 3282);
DISPLAY INVISIBLE (-1795 3282);
FORCEPROP 1 LAST VOLTAGE 0.0V
J 0
(-1795 3282);
DISPLAY 0.340426 (-1795 3282);
PAINT SKYBLUE (-1795 3282);
DISPLAY INVISIBLE (-1795 3282);
FORCEPROP 1 LAST SIZE 1B
J 0
(-1675 3275);
DISPLAY 0.872340 (-1675 3275);
PAINT AQUA (-1675 3275);
DISPLAY INVISIBLE (-1675 3275);
FORCEPROP 1 LAST PATH I172
J 0
(-1675 3325);
DISPLAY 0.872340 (-1675 3325);
PAINT AQUA (-1675 3325);
DISPLAY INVISIBLE (-1675 3325);
FORCEPROP 2 LAST CDS_LIB mstr_symbols
J 0
(-1750 3325);
PAINT MONO (-1750 3325);
DISPLAY INVISIBLE (-1750 3325);
FORCEPROP 1 LAST HDL_POWER GND
J 0
(-1750 3475);
DISPLAY 0.872340 (-1750 3475);
PAINT GREEN (-1750 3475);
DISPLAY INVISIBLE (-1750 3475);
FORCEADD OFFPAGE..2
(-675 2325);
FORCEPROP 2 LAST $XR0 153 
J 0
(-486 2325);
DISPLAY 0.638298 (-486 2325);
PAINT MONO (-486 2325);
FORCEPROP 1 LAST COMMENT_BODY TRUE
J 0
(-720 2230);
DISPLAY 0.872340 (-720 2230);
PAINT GREEN (-720 2230);
DISPLAY INVISIBLE (-720 2230);
FORCEPROP 2 LAST CDS_LIB mstr_standard
J 0
(-675 2325);
PAINT ORANGE (-675 2325);
DISPLAY INVISIBLE (-675 2325);
FORCEPROP 2 LAST PATH I173
J 0
(-475 2375);
DISPLAY 1.021277 (-475 2375);
PAINT ORANGE (-475 2375);
DISPLAY INVISIBLE (-475 2375);
FORCEPROP 1 LAST OFFPAGE TRUE
J 0
(-350 2200);
DISPLAY 0.872340 (-350 2200);
PAINT GREEN (-350 2200);
DISPLAY INVISIBLE (-350 2200);
FORCEADD RES..1
(-1450 2325);
FORCEPROP 1 LAST TOLERANCE 1%
J 0
(-1650 2275);
DISPLAY 0.617021 (-1650 2275);
PAINT SKYBLUE (-1650 2275);
FORCEPROP 1 LAST MATERIAL CHIP
J 0
(-1275 2275);
DISPLAY 0.617021 (-1275 2275);
PAINT SKYBLUE (-1275 2275);
FORCEPROP 1 LAST VALUE 10.0K
J 2
(-1475 2275);
DISPLAY 0.617021 (-1475 2275);
PAINT SKYBLUE (-1475 2275);
FORCEPROP 1 LAST PACK_TYPE 0402
J 0
(-1150 2275);
DISPLAY 0.617021 (-1150 2275);
PAINT SKYBLUE (-1150 2275);
FORCEPROP 1 LASTPIN (-1550 2325) $PN 1
J 0
(-1538 2337);
DISPLAY 0.617021 (-1538 2337);
PAINT ORANGE (-1538 2337);
FORCEPROP 1 LAST LOCATION R3T4
J 0
(-1475 2375);
DISPLAY 0.617021 (-1475 2375);
PAINT AQUA (-1475 2375);
FORCEPROP 1 LASTPIN (-1350 2325) $PN 2
J 0
(-1388 2337);
DISPLAY 0.617021 (-1388 2337);
PAINT ORANGE (-1388 2337);
FORCEPROP 1 LAST PART_NUMBER G21796-016
J 0
(-1550 2225);
DISPLAY 0.617021 (-1550 2225);
PAINT BLUE (-1550 2225);
FORCEPROP 1 LAST WATTAGE 1/16W
J 2
(-1300 2275);
DISPLAY 0.617021 (-1300 2275);
PAINT SKYBLUE (-1300 2275);
FORCEPROP 0 LAST GROUP NI_BIOS_ROM2
J 0
(-1525 2175);
DISPLAY 0.638298 (-1525 2175);
PAINT BROWN (-1525 2175);
DISPLAY BOTH (-1525 2175);
FORCEPROP 2 LAST ROOM SB_SPI
J 0
(-1475 2425);
DISPLAY 1.021277 (-1475 2425);
PAINT ORANGE (-1475 2425);
DISPLAY INVISIBLE (-1475 2425);
FORCEPROP 1 LAST PATH I174
J 0
(-1500 2475);
DISPLAY 0.978723 (-1500 2475);
PAINT WHITE (-1500 2475);
DISPLAY INVISIBLE (-1500 2475);
FORCEPROP 2 LAST CDS_LOCATION R3T4
J 0
(-1475 2375);
DISPLAY 0.617021 (-1475 2375);
PAINT AQUA (-1475 2375);
DISPLAY INVISIBLE (-1475 2375);
FORCEPROP 2 LAST CDS_LIB mstr_discrete
J 0
(-1450 2325);
PAINT ORANGE (-1450 2325);
DISPLAY INVISIBLE (-1450 2325);
FORCEPROP 2 LAST BOM_COST MIO_BIOS_MEM
J 0
(-1475 2475);
DISPLAY 1.021277 (-1475 2475);
PAINT ORANGE (-1475 2475);
DISPLAY INVISIBLE (-1475 2475);
FORCEPROP 2 LAST SEC_TYPE 0402
J 0
(-1500 2525);
DISPLAY 1.021277 (-1500 2525);
PAINT ORANGE (-1500 2525);
DISPLAY INVISIBLE (-1500 2525);
FORCEPROP 2 LAST SEC 1
J 0
(-1500 2525);
PAINT MONO (-1500 2525);
DISPLAY INVISIBLE (-1500 2525);
FORCEADD P3V3_STBY..1
(-1750 2525);
FORCEPROP 3 LASTPIN (-1750 2475) SIG_NAME P3V3_STBY\g
J 0
(-1740 2485);
DISPLAY 0.659574 (-1740 2485);
PAINT MONO (-1740 2485);
DISPLAY INVISIBLE (-1740 2485);
FORCEPROP 1 LAST HDL_POWER P3V3_STBY
J 0
(-2050 2400);
DISPLAY 0.872340 (-2050 2400);
PAINT ORANGE (-2050 2400);
DISPLAY INVISIBLE (-2050 2400);
FORCEPROP 1 LAST BODY_TYPE PLUMBING
J 0
(-1795 2482);
DISPLAY 0.340426 (-1795 2482);
PAINT GREEN (-1795 2482);
DISPLAY INVISIBLE (-1795 2482);
FORCEPROP 1 LAST VOLTAGE 3.3V
J 0
(-1795 2482);
DISPLAY 0.340426 (-1795 2482);
PAINT SKYBLUE (-1795 2482);
DISPLAY INVISIBLE (-1795 2482);
FORCEPROP 1 LAST PATH I175
J 0
(-1705 2527);
DISPLAY 0.340426 (-1705 2527);
PAINT GREEN (-1705 2527);
DISPLAY INVISIBLE (-1705 2527);
FORCEPROP 2 LAST CDS_LIB mstr_symbols
J 0
(-1750 2525);
PAINT ORANGE (-1750 2525);
DISPLAY INVISIBLE (-1750 2525);
FORCEPROP 1 LAST SIZE 1B
J 0
(-1705 2547);
DISPLAY 0.340426 (-1705 2547);
PAINT GREEN (-1705 2547);
DISPLAY INVISIBLE (-1705 2547);
FORCEADD P3V3_STBY..1
(-1750 2075);
FORCEPROP 3 LASTPIN (-1750 2025) SIG_NAME P3V3_STBY\g
J 0
(-1740 2035);
DISPLAY 0.659574 (-1740 2035);
PAINT MONO (-1740 2035);
DISPLAY INVISIBLE (-1740 2035);
FORCEPROP 1 LAST HDL_POWER P3V3_STBY
J 0
(-2050 1950);
DISPLAY 0.872340 (-2050 1950);
PAINT ORANGE (-2050 1950);
DISPLAY INVISIBLE (-2050 1950);
FORCEPROP 1 LAST BODY_TYPE PLUMBING
J 0
(-1795 2032);
DISPLAY 0.340426 (-1795 2032);
PAINT GREEN (-1795 2032);
DISPLAY INVISIBLE (-1795 2032);
FORCEPROP 1 LAST VOLTAGE 3.3V
J 0
(-1795 2032);
DISPLAY 0.340426 (-1795 2032);
PAINT SKYBLUE (-1795 2032);
DISPLAY INVISIBLE (-1795 2032);
FORCEPROP 1 LAST PATH I176
J 0
(-1705 2077);
DISPLAY 0.340426 (-1705 2077);
PAINT GREEN (-1705 2077);
DISPLAY INVISIBLE (-1705 2077);
FORCEPROP 1 LAST SIZE 1B
J 0
(-1705 2097);
DISPLAY 0.340426 (-1705 2097);
PAINT GREEN (-1705 2097);
DISPLAY INVISIBLE (-1705 2097);
FORCEPROP 2 LAST CDS_LIB mstr_symbols
J 0
(-1750 2075);
PAINT MONO (-1750 2075);
DISPLAY INVISIBLE (-1750 2075);
FORCEADD OFFPAGE..2
(-650 1650);
FORCEPROP 2 LAST $XR0 153 
J 0
(-461 1650);
DISPLAY 0.638298 (-461 1650);
PAINT MONO (-461 1650);
FORCEPROP 1 LAST COMMENT_BODY TRUE
J 0
(-695 1555);
DISPLAY 0.872340 (-695 1555);
PAINT GREEN (-695 1555);
DISPLAY INVISIBLE (-695 1555);
FORCEPROP 2 LAST CDS_LIB mstr_standard
J 0
(-650 1650);
PAINT MONO (-650 1650);
DISPLAY INVISIBLE (-650 1650);
FORCEPROP 2 LAST PATH I177
J 0
(-475 1725);
DISPLAY 1.021277 (-475 1725);
PAINT ORANGE (-475 1725);
DISPLAY INVISIBLE (-475 1725);
FORCEPROP 1 LAST OFFPAGE TRUE
J 0
(-325 1525);
DISPLAY 0.872340 (-325 1525);
PAINT GREEN (-325 1525);
DISPLAY INVISIBLE (-325 1525);
FORCEADD RES..2
(-1750 1825);
FORCEPROP 1 LAST PART_NUMBER G21796-016
J 0
(-1710 1775);
DISPLAY 0.617021 (-1710 1775);
PAINT BLUE (-1710 1775);
FORCEPROP 1 LAST PACK_TYPE 0402
J 0
(-1710 1725);
DISPLAY 0.617021 (-1710 1725);
PAINT SKYBLUE (-1710 1725);
FORCEPROP 1 LASTPIN (-1750 1725) $PN 2
J 0
(-1745 1735);
DISPLAY 0.617021 (-1745 1735);
PAINT ORANGE (-1745 1735);
FORCEPROP 1 LASTPIN (-1750 1925) $PN 1
J 0
(-1745 1887);
DISPLAY 0.617021 (-1745 1887);
PAINT ORANGE (-1745 1887);
FORCEPROP 1 LAST LOCATION R3T12
J 0
(-1705 2025);
DISPLAY 0.617021 (-1705 2025);
PAINT AQUA (-1705 2025);
FORCEPROP 0 LAST GROUP NI_BIOS_ROM2
J 0
(-1700 1675);
DISPLAY 0.638298 (-1700 1675);
PAINT BROWN (-1700 1675);
DISPLAY BOTH (-1700 1675);
FORCEPROP 1 LAST TOLERANCE 1%
J 0
(-1705 1925);
DISPLAY 0.617021 (-1705 1925);
PAINT SKYBLUE (-1705 1925);
FORCEPROP 1 LAST MATERIAL CHIP
J 0
(-1710 1825);
DISPLAY 0.617021 (-1710 1825);
PAINT SKYBLUE (-1710 1825);
FORCEPROP 1 LAST VALUE 10.0K
J 0
(-1705 1975);
DISPLAY 0.617021 (-1705 1975);
PAINT SKYBLUE (-1705 1975);
FORCEPROP 1 LAST WATTAGE 1/16W
J 0
(-1710 1875);
DISPLAY 0.617021 (-1710 1875);
PAINT SKYBLUE (-1710 1875);
FORCEPROP 2 LAST CDS_LIB mstr_discrete
J 0
(-1750 1825);
PAINT MONO (-1750 1825);
DISPLAY INVISIBLE (-1750 1825);
FORCEPROP 1 LAST PATH I178
J 0
(-1700 2000);
DISPLAY 0.978723 (-1700 2000);
PAINT WHITE (-1700 2000);
DISPLAY INVISIBLE (-1700 2000);
FORCEPROP 2 LAST CDS_LOCATION R3T12
J 0
(-1705 1950);
DISPLAY 0.617021 (-1705 1950);
PAINT AQUA (-1705 1950);
DISPLAY INVISIBLE (-1705 1950);
FORCEPROP 2 LAST SEC_TYPE 0402
J 0
(-1700 2050);
DISPLAY 1.021277 (-1700 2050);
PAINT ORANGE (-1700 2050);
DISPLAY INVISIBLE (-1700 2050);
FORCEPROP 0 LAST BOM_COST MIO_BIOS_MEM
J 0
(-1700 2150);
DISPLAY 1.021277 (-1700 2150);
PAINT ORANGE (-1700 2150);
DISPLAY INVISIBLE (-1700 2150);
FORCEPROP 2 LAST SEC 1
J 0
(-1700 2050);
DISPLAY 0.680851 (-1700 2050);
PAINT MONO (-1700 2050);
DISPLAY INVISIBLE (-1700 2050);
FORCEPROP 0 LAST ROOM SB_SPI
J 0
(-1700 2050);
DISPLAY 1.021277 (-1700 2050);
PAINT ORANGE (-1700 2050);
DISPLAY INVISIBLE (-1700 2050);
FORCEADD RES..2
(-1750 1450);
FORCEPROP 1 LASTPIN (-1750 1550) $PN 1
J 0
(-1745 1512);
DISPLAY 0.617021 (-1745 1512);
PAINT ORANGE (-1745 1512);
FORCEPROP 1 LASTPIN (-1750 1350) $PN 2
J 0
(-1745 1360);
DISPLAY 0.617021 (-1745 1360);
PAINT ORANGE (-1745 1360);
FORCEPROP 1 LAST TOLERANCE 1%
J 0
(-1705 1475);
DISPLAY 0.617021 (-1705 1475);
PAINT SKYBLUE (-1705 1475);
FORCEPROP 1 LAST VALUE 10.0K
J 0
(-1705 1525);
DISPLAY 0.617021 (-1705 1525);
PAINT SKYBLUE (-1705 1525);
FORCEPROP 1 LAST WATTAGE 1/16W
J 0
(-1710 1425);
DISPLAY 0.617021 (-1710 1425);
PAINT SKYBLUE (-1710 1425);
FORCEPROP 1 LAST PACK_TYPE 0402
J 0
(-1710 1275);
DISPLAY 0.617021 (-1710 1275);
PAINT SKYBLUE (-1710 1275);
FORCEPROP 1 LAST MATERIAL EMPTY
J 0
(-1710 1375);
DISPLAY 0.617021 (-1710 1375);
PAINT RED (-1710 1375);
FORCEPROP 0 LAST GROUP NI_BIOS_ROM2
J 0
(-1675 1225);
DISPLAY 0.638298 (-1675 1225);
PAINT BROWN (-1675 1225);
DISPLAY BOTH (-1675 1225);
FORCEPROP 1 LAST PART_NUMBER G21796-016
J 0
(-1710 1325);
DISPLAY 0.617021 (-1710 1325);
PAINT BLUE (-1710 1325);
FORCEPROP 1 LAST LOCATION R3T9
J 0
(-1705 1575);
DISPLAY 0.617021 (-1705 1575);
PAINT AQUA (-1705 1575);
FORCEPROP 2 LAST CDS_LIB mstr_discrete
J 0
(-1750 1450);
PAINT MONO (-1750 1450);
DISPLAY INVISIBLE (-1750 1450);
FORCEPROP 2 LAST CDS_LOCATION R3T9
J 0
(-1705 1575);
DISPLAY 0.617021 (-1705 1575);
PAINT AQUA (-1705 1575);
DISPLAY INVISIBLE (-1705 1575);
FORCEPROP 1 LAST PATH I179
J 0
(-1700 1625);
DISPLAY 0.978723 (-1700 1625);
PAINT WHITE (-1700 1625);
DISPLAY INVISIBLE (-1700 1625);
FORCEPROP 0 LAST ROOM SB_SPI
J 0
(-1700 1675);
DISPLAY 1.021277 (-1700 1675);
PAINT ORANGE (-1700 1675);
DISPLAY INVISIBLE (-1700 1675);
FORCEPROP 2 LAST SEC 1
J 0
(-1700 1675);
DISPLAY 0.680851 (-1700 1675);
PAINT MONO (-1700 1675);
DISPLAY INVISIBLE (-1700 1675);
FORCEPROP 2 LAST SEC_TYPE 0402
J 0
(-1700 1675);
DISPLAY 1.021277 (-1700 1675);
PAINT ORANGE (-1700 1675);
DISPLAY INVISIBLE (-1700 1675);
FORCEPROP 0 LAST BOM_COST MIO_BIOS_MEM
J 0
(-1700 1775);
DISPLAY 1.021277 (-1700 1775);
PAINT ORANGE (-1700 1775);
DISPLAY INVISIBLE (-1700 1775);
FORCEADD GND..1
(-1750 1225);
FORCEPROP 3 LASTPIN (-1750 1275) SIG_NAME GND\g
J 0
(-1740 1285);
DISPLAY 0.659574 (-1740 1285);
PAINT MONO (-1740 1285);
DISPLAY INVISIBLE (-1740 1285);
FORCEPROP 1 LAST BODY_TYPE PLUMBING
J 0
(-1795 1182);
DISPLAY 0.340426 (-1795 1182);
PAINT GREEN (-1795 1182);
DISPLAY INVISIBLE (-1795 1182);
FORCEPROP 1 LAST VOLTAGE 0.0V
J 0
(-1795 1182);
DISPLAY 0.340426 (-1795 1182);
PAINT SKYBLUE (-1795 1182);
DISPLAY INVISIBLE (-1795 1182);
FORCEPROP 1 LAST PATH I180
J 0
(-1675 1225);
DISPLAY 0.872340 (-1675 1225);
PAINT AQUA (-1675 1225);
DISPLAY INVISIBLE (-1675 1225);
FORCEPROP 1 LAST SIZE 1B
J 0
(-1675 1175);
DISPLAY 0.872340 (-1675 1175);
PAINT AQUA (-1675 1175);
DISPLAY INVISIBLE (-1675 1175);
FORCEPROP 2 LAST CDS_LIB mstr_symbols
J 0
(-1750 1225);
PAINT MONO (-1750 1225);
DISPLAY INVISIBLE (-1750 1225);
FORCEPROP 1 LAST HDL_POWER GND
J 0
(-1750 1375);
DISPLAY 0.872340 (-1750 1375);
PAINT GREEN (-1750 1375);
DISPLAY INVISIBLE (-1750 1375);
FORCEADD RES..1
(-6525 3925);
FORCEPROP 1 LAST PART_NUMBER G21796-074
J 0
(-6650 3975);
DISPLAY 0.638298 (-6650 3975);
PAINT BLUE (-6650 3975);
FORCEPROP 1 LAST PACK_TYPE 0402
J 0
(-6500 4025);
DISPLAY 0.638298 (-6500 4025);
PAINT SKYBLUE (-6500 4025);
FORCEPROP 1 LAST WATTAGE 1/16W
J 0
(-6525 4075);
DISPLAY 0.638298 (-6525 4075);
PAINT SKYBLUE (-6525 4075);
FORCEPROP 1 LAST VALUE 33.2
J 0
(-6500 4132);
DISPLAY 0.617021 (-6500 4132);
PAINT SKYBLUE (-6500 4132);
FORCEPROP 1 LAST MATERIAL CHIP
J 0
(-6650 4025);
DISPLAY 0.638298 (-6650 4025);
PAINT SKYBLUE (-6650 4025);
FORCEPROP 1 LASTPIN (-6625 3925) $PN 1
J 0
(-6613 3937);
DISPLAY 0.617021 (-6613 3937);
PAINT MONO (-6613 3937);
FORCEPROP 1 LASTPIN (-6425 3925) $PN 2
J 0
(-6463 3937);
DISPLAY 0.617021 (-6463 3937);
PAINT MONO (-6463 3937);
FORCEPROP 1 LAST TOLERANCE 1%
J 0
(-6650 4075);
DISPLAY 0.638298 (-6650 4075);
PAINT SKYBLUE (-6650 4075);
FORCEPROP 1 LAST LOCATION R7F29
J 0
(-6657 4132);
DISPLAY 0.617021 (-6657 4132);
PAINT AQUA (-6657 4132);
FORCEPROP 2 LAST CDS_LOCATION R7F29
J 0
(-6532 3982);
DISPLAY 0.617021 (-6532 3982);
PAINT AQUA (-6532 3982);
DISPLAY INVISIBLE (-6532 3982);
FORCEPROP 2 LAST CDS_LIB mstr_discrete
J 1
(-6525 3925);
PAINT ORANGE (-6525 3925);
DISPLAY INVISIBLE (-6525 3925);
FORCEPROP 2 LAST ROOM SB_SPI
J 0
(-6300 3975);
DISPLAY 1.021277 (-6300 3975);
PAINT ORANGE (-6300 3975);
DISPLAY INVISIBLE (-6300 3975);
FORCEPROP 2 LAST BOM_COST MIO_BIOS_MEM
J 0
(-6300 4025);
DISPLAY 1.021277 (-6300 4025);
PAINT ORANGE (-6300 4025);
DISPLAY INVISIBLE (-6300 4025);
FORCEPROP 1 LAST PATH I181
J 0
(-6575 4075);
DISPLAY 0.978723 (-6575 4075);
PAINT WHITE (-6575 4075);
DISPLAY INVISIBLE (-6575 4075);
FORCEPROP 2 LAST SEC 1
J 0
(-6575 4150);
DISPLAY 0.680851 (-6575 4150);
PAINT MONO (-6575 4150);
DISPLAY INVISIBLE (-6575 4150);
FORCEPROP 2 LAST SEC_TYPE 0402
J 0
(-6575 4150);
DISPLAY 1.021277 (-6575 4150);
PAINT ORANGE (-6575 4150);
DISPLAY INVISIBLE (-6575 4150);
FORCEADD OFFPAGE..1
(-7300 3925);
FORCEPROP 2 LAST $XR1 153 
J 0
(-7672 3925);
DISPLAY 0.638298 (-7672 3925);
PAINT MONO (-7672 3925);
FORCEPROP 2 LAST $XR0 154 
J 0
(-7552 3925);
DISPLAY 0.638298 (-7552 3925);
PAINT MONO (-7552 3925);
FORCEPROP 1 LAST OFFPAGE TRUE
J 0
(-6975 3800);
DISPLAY 0.872340 (-6975 3800);
PAINT GREEN (-6975 3800);
DISPLAY INVISIBLE (-6975 3800);
FORCEPROP 2 LAST PATH I182
J 0
(-7250 4000);
DISPLAY 1.021277 (-7250 4000);
PAINT ORANGE (-7250 4000);
DISPLAY INVISIBLE (-7250 4000);
FORCEPROP 2 LAST CDS_LIB mstr_standard
J 0
(-7300 3925);
PAINT ORANGE (-7300 3925);
DISPLAY INVISIBLE (-7300 3925);
FORCEPROP 1 LAST COMMENT_BODY TRUE
J 0
(-7175 3825);
DISPLAY 0.872340 (-7175 3825);
PAINT GREEN (-7175 3825);
DISPLAY INVISIBLE (-7175 3825);
FORCEADD OFFPAGE..1
(-7100 1725);
FORCEPROP 2 LAST $XR1 153 
J 0
(-7472 1725);
DISPLAY 0.638298 (-7472 1725);
PAINT MONO (-7472 1725);
FORCEPROP 2 LAST $XR0 154 
J 0
(-7352 1725);
DISPLAY 0.638298 (-7352 1725);
PAINT MONO (-7352 1725);
FORCEPROP 1 LAST OFFPAGE TRUE
J 0
(-6775 1600);
DISPLAY 0.872340 (-6775 1600);
PAINT GREEN (-6775 1600);
DISPLAY INVISIBLE (-6775 1600);
FORCEPROP 2 LAST PATH I183
J 0
(-7050 1800);
DISPLAY 1.021277 (-7050 1800);
PAINT ORANGE (-7050 1800);
DISPLAY INVISIBLE (-7050 1800);
FORCEPROP 2 LAST CDS_LIB mstr_standard
J 0
(-7100 1725);
PAINT ORANGE (-7100 1725);
DISPLAY INVISIBLE (-7100 1725);
FORCEPROP 1 LAST COMMENT_BODY TRUE
J 0
(-6975 1625);
DISPLAY 0.872340 (-6975 1625);
PAINT GREEN (-6975 1625);
DISPLAY INVISIBLE (-6975 1625);
FORCEADD RES..1
(-6275 1725);
FORCEPROP 1 LAST PACK_TYPE 0402
J 0
(-5850 1775);
DISPLAY 0.638298 (-5850 1775);
PAINT SKYBLUE (-5850 1775);
FORCEPROP 1 LAST TOLERANCE 1%
J 0
(-6500 1775);
DISPLAY 0.638298 (-6500 1775);
PAINT SKYBLUE (-6500 1775);
FORCEPROP 1 LAST LOCATION R3T10
J 0
(-6507 1732);
DISPLAY 0.617021 (-6507 1732);
PAINT AQUA (-6507 1732);
FORCEPROP 1 LAST WATTAGE 1/16W
J 0
(-6400 1775);
DISPLAY 0.638298 (-6400 1775);
PAINT SKYBLUE (-6400 1775);
FORCEPROP 1 LASTPIN (-6375 1725) $PN 1
J 0
(-6363 1737);
DISPLAY 0.617021 (-6363 1737);
PAINT MONO (-6363 1737);
FORCEPROP 1 LASTPIN (-6175 1725) $PN 2
J 0
(-6213 1737);
DISPLAY 0.617021 (-6213 1737);
PAINT MONO (-6213 1737);
FORCEPROP 1 LAST VALUE 33.2
J 0
(-6150 1732);
DISPLAY 0.617021 (-6150 1732);
PAINT SKYBLUE (-6150 1732);
FORCEPROP 1 LAST MATERIAL CHIP
J 0
(-6250 1775);
DISPLAY 0.638298 (-6250 1775);
PAINT SKYBLUE (-6250 1775);
FORCEPROP 1 LAST PART_NUMBER G21796-074
J 0
(-6100 1775);
DISPLAY 0.638298 (-6100 1775);
PAINT BLUE (-6100 1775);
FORCEPROP 0 LAST GROUP NI_BIOS_ROM2
J 0
(-5725 1775);
DISPLAY 0.638298 (-5725 1775);
PAINT BROWN (-5725 1775);
DISPLAY BOTH (-5725 1775);
FORCEPROP 2 LAST CDS_LIB mstr_discrete
J 1
(-6275 1725);
PAINT ORANGE (-6275 1725);
DISPLAY INVISIBLE (-6275 1725);
FORCEPROP 2 LAST CDS_LOCATION R3T10
J 0
(-6282 1782);
DISPLAY 0.617021 (-6282 1782);
PAINT AQUA (-6282 1782);
DISPLAY INVISIBLE (-6282 1782);
FORCEPROP 1 LAST PATH I184
J 0
(-6325 1875);
DISPLAY 0.978723 (-6325 1875);
PAINT WHITE (-6325 1875);
DISPLAY INVISIBLE (-6325 1875);
FORCEPROP 2 LAST ROOM SB_SPI
J 0
(-6050 1775);
DISPLAY 1.021277 (-6050 1775);
PAINT ORANGE (-6050 1775);
DISPLAY INVISIBLE (-6050 1775);
FORCEPROP 2 LAST BOM_COST MIO_BIOS_MEM
J 0
(-6050 1825);
DISPLAY 1.021277 (-6050 1825);
PAINT ORANGE (-6050 1825);
DISPLAY INVISIBLE (-6050 1825);
FORCEPROP 2 LAST SEC_TYPE 0402
J 0
(-6325 1950);
DISPLAY 1.021277 (-6325 1950);
PAINT ORANGE (-6325 1950);
DISPLAY INVISIBLE (-6325 1950);
FORCEPROP 2 LAST SEC 1
J 0
(-6325 1950);
DISPLAY 0.680851 (-6325 1950);
PAINT MONO (-6325 1950);
DISPLAY INVISIBLE (-6325 1950);
FORCEADD W25Q256FVFIG-GP..1
(-4950 1800);
FORCEPROP 1 LAST LOCATION U3T1
J 0
(-5225 2200);
DISPLAY 0.617021 (-5225 2200);
PAINT GREEN (-5225 2200);
FORCEPROP 1 LAST VALUE W25Q256FVFIG-GP
J 0
(-5225 1375);
DISPLAY 0.617021 (-5225 1375);
PAINT GREEN (-5225 1375);
FORCEPROP 2 LASTPIN (-5375 1575) $PN 9
J 2
(-5385 1585);
DISPLAY 0.808511 (-5385 1585);
PAINT ORANGE (-5385 1585);
FORCEPROP 2 LASTPIN (-4525 1975) $PN 6
J 0
(-4515 1985);
DISPLAY 0.808511 (-4515 1985);
PAINT ORANGE (-4515 1985);
FORCEPROP 2 LASTPIN (-4525 2025) $PN 5
J 0
(-4515 2035);
DISPLAY 0.808511 (-4515 2035);
PAINT ORANGE (-4515 2035);
FORCEPROP 2 LASTPIN (-5375 1675) $PN 8
J 2
(-5385 1685);
DISPLAY 0.808511 (-5385 1685);
PAINT ORANGE (-5385 1685);
FORCEPROP 2 LASTPIN (-4525 1925) $PN 11
J 0
(-4515 1935);
DISPLAY 0.808511 (-4515 1935);
PAINT ORANGE (-4515 1935);
FORCEPROP 2 LASTPIN (-5375 1725) $PN 15
J 2
(-5385 1735);
DISPLAY 0.808511 (-5385 1735);
PAINT ORANGE (-5385 1735);
FORCEPROP 2 LASTPIN (-4525 1775) $PN 14
J 0
(-4515 1785);
DISPLAY 0.808511 (-4515 1785);
PAINT ORANGE (-4515 1785);
FORCEPROP 2 LASTPIN (-5375 1925) $PN 3
J 2
(-5385 1935);
DISPLAY 0.808511 (-5385 1935);
PAINT ORANGE (-5385 1935);
FORCEPROP 2 LASTPIN (-5375 1525) $PN 1
J 2
(-5385 1535);
DISPLAY 0.808511 (-5385 1535);
PAINT ORANGE (-5385 1535);
FORCEPROP 2 LASTPIN (-4525 2075) $PN 4
J 0
(-4515 2085);
DISPLAY 0.808511 (-4515 2085);
PAINT ORANGE (-4515 2085);
FORCEPROP 2 LASTPIN (-5375 2075) $PN 2
J 2
(-5385 2085);
DISPLAY 0.808511 (-5385 2085);
PAINT ORANGE (-5385 2085);
FORCEPROP 2 LASTPIN (-5375 1825) $PN 16
J 2
(-5385 1835);
DISPLAY 0.808511 (-5385 1835);
PAINT ORANGE (-5385 1835);
FORCEPROP 2 LASTPIN (-5375 1875) $PN 7
J 2
(-5385 1885);
DISPLAY 0.808511 (-5385 1885);
PAINT ORANGE (-5385 1885);
FORCEPROP 2 LASTPIN (-4525 1525) $PN 10
J 0
(-4515 1535);
DISPLAY 0.808511 (-4515 1535);
PAINT ORANGE (-4515 1535);
FORCEPROP 0 LAST GROUP NI_BIOS_ROM2
J 0
(-5225 1325);
DISPLAY 0.638298 (-5225 1325);
PAINT BROWN (-5225 1325);
DISPLAY BOTH (-5225 1325);
FORCEPROP 2 LASTPIN (-4525 1825) $PN 13
J 0
(-4515 1835);
DISPLAY 0.808511 (-4515 1835);
PAINT ORANGE (-4515 1835);
FORCEPROP 2 LASTPIN (-4525 1875) $PN 12
J 0
(-4515 1885);
DISPLAY 0.808511 (-4515 1885);
PAINT ORANGE (-4515 1885);
FORCEPROP 1 LAST PACK_TYPE MEMORY-G4
J 0
(-4950 1800);
DISPLAY 0.617021 (-4950 1800);
PAINT GREEN (-4950 1800);
DISPLAY INVISIBLE (-4950 1800);
FORCEPROP 2 LAST SEC 1
J 0
(-5225 2250);
DISPLAY 0.680851 (-5225 2250);
PAINT MONO (-5225 2250);
DISPLAY INVISIBLE (-5225 2250);
FORCEPROP 2 LAST SEC_TYPE MEMORY-G4
J 0
(-5225 2250);
DISPLAY 1.021277 (-5225 2250);
PAINT ORANGE (-5225 2250);
DISPLAY INVISIBLE (-5225 2250);
FORCEPROP 1 LAST PART_NUMBER 72.25256.H01
J 0
(-4950 1800);
DISPLAY 0.617021 (-4950 1800);
PAINT GREEN (-4950 1800);
DISPLAY INVISIBLE (-4950 1800);
FORCEPROP 2 LAST CDS_LIB w_hdl
J 0
(-4950 1800);
PAINT MONO (-4950 1800);
DISPLAY INVISIBLE (-4950 1800);
FORCEPROP 1 LAST PATH I185
J 0
(-4950 1800);
DISPLAY 0.617021 (-4950 1800);
PAINT GREEN (-4950 1800);
DISPLAY INVISIBLE (-4950 1800);
FORCEPROP 1 LAST CDS_LMAN_SYM_OUTLINE -275,375,275,-375
J 0
(-4950 1800);
DISPLAY 0.468085 (-4950 1800);
PAINT GREEN (-4950 1800);
DISPLAY INVISIBLE (-4950 1800);
FORCEADD GND..1
(-4325 1400);
FORCEPROP 3 LASTPIN (-4325 1450) SIG_NAME GND\g
J 0
(-4315 1460);
DISPLAY 0.659574 (-4315 1460);
PAINT MONO (-4315 1460);
DISPLAY INVISIBLE (-4315 1460);
FORCEPROP 1 LAST HDL_POWER GND
J 0
(-4325 1550);
DISPLAY 1.170213 (-4325 1550);
PAINT GREEN (-4325 1550);
DISPLAY INVISIBLE (-4325 1550);
FORCEPROP 2 LAST CDS_LIB mstr_symbols
J 0
(-4325 1400);
PAINT ORANGE (-4325 1400);
DISPLAY INVISIBLE (-4325 1400);
FORCEPROP 1 LAST VOLTAGE 0
J 0
(-4325 1400);
PAINT SKYBLUE (-4325 1400);
DISPLAY INVISIBLE (-4325 1400);
FORCEPROP 1 LAST SIZE 1B
J 0
(-4250 1350);
DISPLAY 1.170213 (-4250 1350);
PAINT GREEN (-4250 1350);
DISPLAY INVISIBLE (-4250 1350);
FORCEPROP 1 LAST BODY_TYPE PLUMBING
J 0
(-4370 1357);
DISPLAY 0.340426 (-4370 1357);
PAINT GREEN (-4370 1357);
DISPLAY INVISIBLE (-4370 1357);
FORCEPROP 1 LAST PATH I186
J 0
(-4250 1400);
DISPLAY 0.872340 (-4250 1400);
PAINT AQUA (-4250 1400);
DISPLAY INVISIBLE (-4250 1400);
FORCEADD RES..1
(-6550 3625);
FORCEPROP 1 LAST MATERIAL CHIP
J 0
(-6400 3575);
DISPLAY 0.617021 (-6400 3575);
PAINT SKYBLUE (-6400 3575);
FORCEPROP 1 LAST PACK_TYPE 0402
J 0
(-6300 3575);
DISPLAY 0.617021 (-6300 3575);
PAINT SKYBLUE (-6300 3575);
FORCEPROP 1 LAST PART_NUMBER G21497-005
J 0
(-6675 3525);
DISPLAY 0.617021 (-6675 3525);
PAINT BLUE (-6675 3525);
FORCEPROP 1 LASTPIN (-6650 3625) $PN 1
J 0
(-6638 3637);
DISPLAY 0.617021 (-6638 3637);
PAINT MONO (-6638 3637);
FORCEPROP 1 LAST TOLERANCE 5%
J 0
(-6475 3575);
DISPLAY 0.617021 (-6475 3575);
PAINT SKYBLUE (-6475 3575);
FORCEPROP 1 LASTPIN (-6450 3625) $PN 2
J 0
(-6488 3637);
DISPLAY 0.617021 (-6488 3637);
PAINT MONO (-6488 3637);
FORCEPROP 1 LAST LOCATION R7W5
J 0
(-6600 3675);
DISPLAY 0.617021 (-6600 3675);
PAINT AQUA (-6600 3675);
FORCEPROP 1 LAST VALUE 0.0
J 2
(-6575 3575);
DISPLAY 0.617021 (-6575 3575);
PAINT SKYBLUE (-6575 3575);
FORCEPROP 1 LAST WATTAGE 1/16W
J 2
(-6675 3575);
DISPLAY 0.617021 (-6675 3575);
PAINT SKYBLUE (-6675 3575);
FORCEPROP 2 LAST CDS_LOCATION R7W5
J 0
(-6600 3675);
DISPLAY 0.617021 (-6600 3675);
PAINT AQUA (-6600 3675);
DISPLAY INVISIBLE (-6600 3675);
FORCEPROP 1 LAST PATH I187
J 0
(-6600 3775);
DISPLAY 0.978723 (-6600 3775);
PAINT WHITE (-6600 3775);
DISPLAY INVISIBLE (-6600 3775);
FORCEPROP 2 LAST ROOM MIO_BIOS_MEM
J 0
(-6600 3765);
DISPLAY 0.787234 (-6600 3765);
PAINT SKYBLUE (-6600 3765);
DISPLAY INVISIBLE (-6600 3765);
FORCEPROP 2 LAST $SEC 1
J 0
(-6600 3825);
DISPLAY 0.936170 (-6600 3825);
PAINT MONO (-6600 3825);
DISPLAY INVISIBLE (-6600 3825);
FORCEPROP 2 LAST CDS_SEC 1
J 0
(-6600 3825);
DISPLAY 1.404255 (-6600 3825);
PAINT ORANGE (-6600 3825);
DISPLAY INVISIBLE (-6600 3825);
FORCEPROP 2 LAST CDS_LIB mstr_discrete
J 0
(-6550 3625);
PAINT RED (-6550 3625);
DISPLAY INVISIBLE (-6550 3625);
FORCEADD OFFPAGE..1
(-7300 3625);
FORCEPROP 2 LAST $XR0 154 
J 0
(-7552 3625);
DISPLAY 0.638298 (-7552 3625);
PAINT MONO (-7552 3625);
FORCEPROP 2 LAST PATH I188
J 0
(-7550 3675);
DISPLAY 1.021277 (-7550 3675);
PAINT ORANGE (-7550 3675);
DISPLAY INVISIBLE (-7550 3675);
FORCEPROP 1 LAST OFFPAGE TRUE
J 0
(-6975 3500);
PAINT GREEN (-6975 3500);
DISPLAY INVISIBLE (-6975 3500);
FORCEPROP 2 LAST CDS_LIB mstr_standard
J 0
(-7300 3625);
DISPLAY 1.531915 (-7300 3625);
PAINT ORANGE (-7300 3625);
DISPLAY INVISIBLE (-7300 3625);
FORCEPROP 1 LAST COMMENT_BODY TRUE
J 0
(-7175 3525);
DISPLAY 0.978723 (-7175 3525);
PAINT PEACH (-7175 3525);
DISPLAY INVISIBLE (-7175 3525);
FORCEADD RES..2
R 2
(-5950 4425);
FORCEPROP 1 LAST MATERIAL EMPTY
J 2
(-5990 4450);
DISPLAY 0.617021 (-5990 4450);
PAINT RED (-5990 4450);
FORCEPROP 1 LAST TOLERANCE 1%
J 2
(-5995 4400);
DISPLAY 0.617021 (-5995 4400);
PAINT SKYBLUE (-5995 4400);
FORCEPROP 1 LAST WATTAGE 1/16W
J 2
(-5990 4350);
DISPLAY 0.617021 (-5990 4350);
PAINT SKYBLUE (-5990 4350);
FORCEPROP 1 LAST LOCATION R7F6
J 2
(-5995 4550);
DISPLAY 0.617021 (-5995 4550);
PAINT AQUA (-5995 4550);
FORCEPROP 1 LAST VALUE 4.75K
J 2
(-5995 4500);
DISPLAY 0.617021 (-5995 4500);
PAINT SKYBLUE (-5995 4500);
FORCEPROP 1 LAST PART_NUMBER G21796-072
J 2
(-5990 4300);
DISPLAY 0.617021 (-5990 4300);
PAINT BLUE (-5990 4300);
FORCEPROP 1 LASTPIN (-5950 4325) $PN 2
J 2
(-5955 4335);
DISPLAY 0.617021 (-5955 4335);
PAINT ORANGE (-5955 4335);
FORCEPROP 1 LASTPIN (-5950 4525) $PN 1
J 2
(-5955 4487);
DISPLAY 0.617021 (-5955 4487);
PAINT ORANGE (-5955 4487);
FORCEPROP 1 LAST PACK_TYPE 0402
J 2
(-5990 4250);
DISPLAY 0.617021 (-5990 4250);
PAINT SKYBLUE (-5990 4250);
FORCEPROP 2 LAST CDS_LIB mstr_discrete
J 0
(-5950 4425);
PAINT ORANGE (-5950 4425);
DISPLAY INVISIBLE (-5950 4425);
FORCEPROP 2 LAST CDS_LOCATION R7F6
J 2
(-5995 4550);
DISPLAY 0.617021 (-5995 4550);
PAINT AQUA (-5995 4550);
DISPLAY INVISIBLE (-5995 4550);
FORCEPROP 2 LAST ROOM SB_SPI
J 0
(-5975 4600);
DISPLAY 1.021277 (-5975 4600);
PAINT ORANGE (-5975 4600);
DISPLAY INVISIBLE (-5975 4600);
FORCEPROP 1 LAST PATH I90
J 2
(-6000 4600);
DISPLAY 0.978723 (-6000 4600);
PAINT WHITE (-6000 4600);
DISPLAY INVISIBLE (-6000 4600);
FORCEPROP 2 LAST NO_XNET_CONNECTION 1
J 0
(-6000 4650);
PAINT MONO (-6000 4650);
DISPLAY INVISIBLE (-6000 4650);
FORCEPROP 2 LAST SEC 1
J 0
(-6000 4650);
DISPLAY 0.680851 (-6000 4650);
PAINT MONO (-6000 4650);
DISPLAY INVISIBLE (-6000 4650);
FORCEPROP 2 LAST SEC_TYPE 0402
J 0
(-6000 4650);
DISPLAY 1.021277 (-6000 4650);
PAINT ORANGE (-6000 4650);
DISPLAY INVISIBLE (-6000 4650);
FORCEPROP 2 LAST BOM_COST MIO_BIOS_MEM
J 0
(-5975 4650);
DISPLAY 1.021277 (-5975 4650);
PAINT ORANGE (-5975 4650);
DISPLAY INVISIBLE (-5975 4650);
FORCEADD GND..1
(-4000 3600);
FORCEPROP 3 LASTPIN (-4000 3650) SIG_NAME GND\g
J 0
(-3990 3660);
DISPLAY 0.659574 (-3990 3660);
PAINT MONO (-3990 3660);
DISPLAY INVISIBLE (-3990 3660);
FORCEPROP 1 LAST BODY_TYPE PLUMBING
J 0
(-4045 3557);
DISPLAY 0.340426 (-4045 3557);
PAINT GREEN (-4045 3557);
DISPLAY INVISIBLE (-4045 3557);
FORCEPROP 1 LAST VOLTAGE 0
J 0
(-4000 3600);
PAINT SKYBLUE (-4000 3600);
DISPLAY INVISIBLE (-4000 3600);
FORCEPROP 1 LAST HDL_POWER GND
J 0
(-4000 3750);
DISPLAY 1.170213 (-4000 3750);
PAINT GREEN (-4000 3750);
DISPLAY INVISIBLE (-4000 3750);
FORCEPROP 2 LAST CDS_LIB mstr_symbols
J 0
(-4000 3600);
PAINT ORANGE (-4000 3600);
DISPLAY INVISIBLE (-4000 3600);
FORCEPROP 1 LAST PATH I91
J 0
(-3925 3600);
DISPLAY 0.872340 (-3925 3600);
PAINT AQUA (-3925 3600);
DISPLAY INVISIBLE (-3925 3600);
FORCEPROP 1 LAST SIZE 1B
J 0
(-3925 3550);
DISPLAY 1.170213 (-3925 3550);
PAINT GREEN (-3925 3550);
DISPLAY INVISIBLE (-3925 3550);
FORCEADD RES..2
R 2
(-6250 4425);
FORCEPROP 1 LAST TOLERANCE 1%
J 2
(-6295 4400);
DISPLAY 0.617021 (-6295 4400);
PAINT SKYBLUE (-6295 4400);
FORCEPROP 1 LAST PART_NUMBER G21796-072
J 2
(-6290 4300);
DISPLAY 0.617021 (-6290 4300);
PAINT BLUE (-6290 4300);
FORCEPROP 1 LAST LOCATION R7F5
J 2
(-6295 4550);
DISPLAY 0.617021 (-6295 4550);
PAINT AQUA (-6295 4550);
FORCEPROP 1 LAST WATTAGE 1/16W
J 2
(-6290 4350);
DISPLAY 0.617021 (-6290 4350);
PAINT SKYBLUE (-6290 4350);
FORCEPROP 1 LAST VALUE 4.75K
J 2
(-6295 4500);
DISPLAY 0.617021 (-6295 4500);
PAINT SKYBLUE (-6295 4500);
FORCEPROP 1 LASTPIN (-6250 4325) $PN 2
J 2
(-6255 4335);
DISPLAY 0.617021 (-6255 4335);
PAINT ORANGE (-6255 4335);
FORCEPROP 1 LASTPIN (-6250 4525) $PN 1
J 2
(-6255 4487);
DISPLAY 0.617021 (-6255 4487);
PAINT ORANGE (-6255 4487);
FORCEPROP 1 LAST PACK_TYPE 0402
J 2
(-6290 4250);
DISPLAY 0.617021 (-6290 4250);
PAINT SKYBLUE (-6290 4250);
FORCEPROP 1 LAST MATERIAL CHIP
J 2
(-6290 4450);
DISPLAY 0.617021 (-6290 4450);
PAINT SKYBLUE (-6290 4450);
FORCEPROP 2 LAST CDS_LOCATION R7F5
J 2
(-6295 4550);
DISPLAY 0.617021 (-6295 4550);
PAINT AQUA (-6295 4550);
DISPLAY INVISIBLE (-6295 4550);
FORCEPROP 2 LAST CDS_LIB mstr_discrete
J 0
(-6250 4425);
PAINT ORANGE (-6250 4425);
DISPLAY INVISIBLE (-6250 4425);
FORCEPROP 2 LAST ROOM SB_SPI
J 0
(-6275 4600);
DISPLAY 1.021277 (-6275 4600);
PAINT ORANGE (-6275 4600);
DISPLAY INVISIBLE (-6275 4600);
FORCEPROP 1 LAST PATH I94
J 2
(-6300 4600);
DISPLAY 0.978723 (-6300 4600);
PAINT WHITE (-6300 4600);
DISPLAY INVISIBLE (-6300 4600);
FORCEPROP 2 LAST SEC_TYPE 0402
J 0
(-6300 4650);
DISPLAY 1.021277 (-6300 4650);
PAINT ORANGE (-6300 4650);
DISPLAY INVISIBLE (-6300 4650);
FORCEPROP 2 LAST BOM_COST MIO_BIOS_MEM
J 0
(-6275 4650);
DISPLAY 1.021277 (-6275 4650);
PAINT ORANGE (-6275 4650);
DISPLAY INVISIBLE (-6275 4650);
FORCEPROP 2 LAST SEC 1
J 0
(-6300 4650);
DISPLAY 0.680851 (-6300 4650);
PAINT MONO (-6300 4650);
DISPLAY INVISIBLE (-6300 4650);
FORCEPROP 2 LAST NO_XNET_CONNECTION 1
J 0
(-6300 4650);
PAINT MONO (-6300 4650);
DISPLAY INVISIBLE (-6300 4650);
FORCEADD P3V3_STBY..1
(-6450 4825);
FORCEPROP 3 LASTPIN (-6450 4775) SIG_NAME P3V3_STBY\g
J 0
(-6440 4785);
DISPLAY 0.659574 (-6440 4785);
PAINT MONO (-6440 4785);
DISPLAY INVISIBLE (-6440 4785);
FORCEPROP 1 LAST HDL_POWER P3V3_STBY
J 0
(-6750 4700);
DISPLAY 0.872340 (-6750 4700);
PAINT ORANGE (-6750 4700);
DISPLAY INVISIBLE (-6750 4700);
FORCEPROP 1 LAST VOLTAGE 3.3V
J 0
(-6495 4782);
DISPLAY 0.340426 (-6495 4782);
PAINT SKYBLUE (-6495 4782);
DISPLAY INVISIBLE (-6495 4782);
FORCEPROP 2 LAST CDS_LIB mstr_symbols
J 0
(-6450 4825);
PAINT ORANGE (-6450 4825);
DISPLAY INVISIBLE (-6450 4825);
FORCEPROP 1 LAST SIZE 1B
J 0
(-6405 4847);
DISPLAY 0.340426 (-6405 4847);
PAINT GREEN (-6405 4847);
DISPLAY INVISIBLE (-6405 4847);
FORCEPROP 1 LAST BODY_TYPE PLUMBING
J 0
(-6495 4782);
DISPLAY 0.340426 (-6495 4782);
PAINT GREEN (-6495 4782);
DISPLAY INVISIBLE (-6495 4782);
FORCEPROP 1 LAST PATH I95
J 0
(-6405 4827);
DISPLAY 0.340426 (-6405 4827);
PAINT GREEN (-6405 4827);
DISPLAY INVISIBLE (-6405 4827);
FORCEADD RES..1
(-6275 3975);
FORCEPROP 1 LAST PART_NUMBER G21796-074
J 0
(-6350 4025);
DISPLAY 0.638298 (-6350 4025);
PAINT BLUE (-6350 4025);
FORCEPROP 1 LAST LOCATION R7F4
J 0
(-6357 4182);
DISPLAY 0.617021 (-6357 4182);
PAINT AQUA (-6357 4182);
FORCEPROP 1 LASTPIN (-6375 3975) $PN 1
J 0
(-6363 3987);
DISPLAY 0.617021 (-6363 3987);
PAINT MONO (-6363 3987);
FORCEPROP 1 LAST MATERIAL CHIP
J 0
(-6350 4075);
DISPLAY 0.638298 (-6350 4075);
PAINT SKYBLUE (-6350 4075);
FORCEPROP 1 LAST WATTAGE 1/16W
J 0
(-6200 4125);
DISPLAY 0.638298 (-6200 4125);
PAINT SKYBLUE (-6200 4125);
FORCEPROP 1 LAST VALUE 33.2
J 0
(-6200 4182);
DISPLAY 0.617021 (-6200 4182);
PAINT SKYBLUE (-6200 4182);
FORCEPROP 1 LAST PACK_TYPE 0402
J 0
(-6200 4075);
DISPLAY 0.638298 (-6200 4075);
PAINT SKYBLUE (-6200 4075);
FORCEPROP 1 LASTPIN (-6175 3975) $PN 2
J 0
(-6213 3987);
DISPLAY 0.617021 (-6213 3987);
PAINT MONO (-6213 3987);
FORCEPROP 1 LAST TOLERANCE 1%
J 0
(-6350 4125);
DISPLAY 0.638298 (-6350 4125);
PAINT SKYBLUE (-6350 4125);
FORCEPROP 2 LAST CDS_LIB mstr_discrete
J 1
(-6275 3975);
PAINT ORANGE (-6275 3975);
DISPLAY INVISIBLE (-6275 3975);
FORCEPROP 2 LAST CDS_LOCATION R7F4
J 0
(-6157 3932);
DISPLAY 0.617021 (-6157 3932);
PAINT AQUA (-6157 3932);
DISPLAY INVISIBLE (-6157 3932);
FORCEPROP 2 LAST ROOM SB_SPI
J 0
(-6050 4025);
DISPLAY 1.021277 (-6050 4025);
PAINT ORANGE (-6050 4025);
DISPLAY INVISIBLE (-6050 4025);
FORCEPROP 2 LAST BOM_COST MIO_BIOS_MEM
J 0
(-6050 4075);
DISPLAY 1.021277 (-6050 4075);
PAINT ORANGE (-6050 4075);
DISPLAY INVISIBLE (-6050 4075);
FORCEPROP 1 LAST PATH I98
J 0
(-6325 4125);
DISPLAY 0.978723 (-6325 4125);
PAINT WHITE (-6325 4125);
DISPLAY INVISIBLE (-6325 4125);
FORCEPROP 2 LAST SEC 1
J 0
(-6325 4200);
DISPLAY 0.680851 (-6325 4200);
PAINT MONO (-6325 4200);
DISPLAY INVISIBLE (-6325 4200);
FORCEPROP 2 LAST SEC_TYPE 0402
J 0
(-6325 4200);
DISPLAY 1.021277 (-6325 4200);
PAINT ORANGE (-6325 4200);
DISPLAY INVISIBLE (-6325 4200);
FORCEADD DNS..2
(-1745 3545);
PAINT RED (-1745 3545);
FORCEPROP 1 LAST COMMENT_BODY TRUE
R 1
J 0
(-1670 3320);
DISPLAY 0.872340 (-1670 3320);
PAINT GREEN (-1670 3320);
DISPLAY INVISIBLE (-1670 3320);
FORCEPROP 2 LAST CDS_LIB mstr_misc
J 0
(-1745 3545);
PAINT ORANGE (-1745 3545);
DISPLAY INVISIBLE (-1745 3545);
FORCEADD INTEL_CORP_BPAGE..1
(0 0);
FORCEPROP 1 LAST CDS_CON_LAST_MODIFIED Fri Jun 16 17:48:57 2017
J 0
(-1425 325);
DISPLAY 1.361702 (-1425 325);
PAINT GREEN (-1425 325);
DISPLAY INVISIBLE (-1425 325);
FORCEPROP 1 LAST CUSTOM_TXT_CDS <CURRENT_DESIGN_SHEET> OF <TOTAL_DESIGN_SHEETS>
J 0
(-500 25);
PAINT ORANGE (-500 25);
FORCEPROP 1 LAST CUSTOM_TXT_CDS <CON_LAST_MODIFIED>
J 0
(-4000 100);
PAINT ORANGE (-4000 100);
FORCEPROP 2 LAST CUSTOM_TXT_CDS <XR_PAGE_TITLE>
J 0
(-7890 5250);
DISPLAY 0.638298 (-7890 5250);
PAINT PINK (-7890 5250);
DISPLAY INVISIBLE (-7890 5250);
FORCEPROP 1 LAST SCH_TITLE BMC AND PCH SHARED SPI FLASH
J 0
(-7950 50);
DISPLAY 1.212766 (-7950 50);
PAINT ORANGE (-7950 50);
FORCEPROP 2 LAST PAGE_BORDER TRUE
J 0
(-7890 5250);
DISPLAY 0.851064 (-7890 5250);
PAINT PINK (-7890 5250);
DISPLAY INVISIBLE (-7890 5250);
FORCEPROP 2 LAST CDS_LIB mstr_symbols
J 0
(0 0);
DISPLAY 1.361702 (0 0);
PAINT ORANGE (0 0);
DISPLAY INVISIBLE (0 0);
FORCEPROP 1 LAST COMMENT_BODY TRUE
J 0
(12 12);
DISPLAY 0.617021 (12 12);
PAINT GREEN (12 12);
DISPLAY INVISIBLE (12 12);
FORCEPROP 2 LAST CDS_XR_PAGE_TITLE CR-153 : @BASEBOARD_FAB2_LIB.BASEBOARD_FAB2(SCH_1):PAGE153
J 0
(-7890 5250);
DISPLAY 0.638298 (-7890 5250);
PAINT PINK (-7890 5250);
DISPLAY INVISIBLE (-7890 5250);
FORCEADD CAD_NOTE..1
(-3100 4550);
FORCEPROP 0 LAST L1 PLACE CAPS NEAR VCC PIN ON W25Q256 COMPONENT
J 0
(-3250 4425);
DISPLAY 0.808511 (-3250 4425);
PAINT ORANGE (-3250 4425);
FORCEPROP 2 LAST CDS_LIB mstr_symbols
J 0
(-3100 4550);
PAINT ORANGE (-3100 4550);
DISPLAY INVISIBLE (-3100 4550);
FORCEPROP 1 LAST COMMENT_BODY TRUE
J 0
(-3075 4650);
DISPLAY 0.978723 (-3075 4650);
PAINT ORANGE (-3075 4650);
DISPLAY INVISIBLE (-3075 4650);
FORCEADD DESIGN_NOTE..1
(-3200 3925);
FORCEPROP 0 LAST L3 64MB FLASH = H60781-001
J 0
(-3400 3500);
DISPLAY 1.021277 (-3400 3500);
PAINT ORANGE (-3400 3500);
FORCEPROP 0 LAST L4 MICRON MT25QL512ABA8ESF
J 0
(-3400 3425);
DISPLAY 1.021277 (-3400 3425);
PAINT ORANGE (-3400 3425);
FORCEPROP 0 LAST L2 WINBOND W25Q256FVFIQ
J 0
(-3400 3700);
DISPLAY 1.021277 (-3400 3700);
PAINT ORANGE (-3400 3700);
FORCEPROP 0 LAST L1 32MB FLASH = H25002-001
J 0
(-3400 3800);
DISPLAY 1.021277 (-3400 3800);
PAINT ORANGE (-3400 3800);
FORCEPROP 1 LAST COMMENT_BODY TRUE
J 0
(-3175 4025);
DISPLAY 0.978723 (-3175 4025);
PAINT ORANGE (-3175 4025);
DISPLAY INVISIBLE (-3175 4025);
FORCEPROP 2 LAST CDS_LIB mstr_symbols
J 0
(-3200 3925);
PAINT ORANGE (-3200 3925);
DISPLAY INVISIBLE (-3200 3925);
FORCEADD DNS..2
(-5945 4420);
PAINT RED (-5945 4420);
FORCEPROP 1 LAST COMMENT_BODY TRUE
R 1
J 0
(-5870 4195);
DISPLAY 0.872340 (-5870 4195);
PAINT GREEN (-5870 4195);
DISPLAY INVISIBLE (-5870 4195);
FORCEPROP 2 LAST CDS_LIB mstr_misc
J 0
(-5945 4420);
PAINT ORANGE (-5945 4420);
DISPLAY INVISIBLE (-5945 4420);
FORCEADD DNS..2
(-1745 1445);
PAINT RED (-1745 1445);
FORCEPROP 1 LAST COMMENT_BODY TRUE
R 1
J 0
(-1670 1220);
DISPLAY 0.872340 (-1670 1220);
PAINT GREEN (-1670 1220);
DISPLAY INVISIBLE (-1670 1220);
FORCEPROP 2 LAST CDS_LIB mstr_misc
J 0
(-1745 1445);
PAINT ORANGE (-1745 1445);
DISPLAY INVISIBLE (-1745 1445);
FORCEADD CAD_NOTE..1
(-5050 3150);
FORCEPROP 0 LAST L1 THIS PART WILL BE IN SOCKET, PLEASE
J 0
(-5200 3050);
DISPLAY 0.617021 (-5200 3050);
PAINT WHITE (-5200 3050);
FORCEPROP 0 LAST L2 USE ALT SYMBOL ASSOCIATED WITH PART FOOTPRINT
J 0
(-5200 3000);
DISPLAY 0.617021 (-5200 3000);
PAINT WHITE (-5200 3000);
FORCEPROP 2 LAST CDS_LIB mstr_symbols
J 0
(-5050 3150);
PAINT WHITE (-5050 3150);
DISPLAY INVISIBLE (-5050 3150);
FORCEPROP 1 LAST COMMENT_BODY TRUE
J 0
(-5025 3250);
DISPLAY 1.319149 (-5025 3250);
PAINT WHITE (-5025 3250);
DISPLAY INVISIBLE (-5025 3250);
FORCEADD DNS..2
(-5870 2320);
PAINT RED (-5870 2320);
FORCEPROP 1 LAST COMMENT_BODY TRUE
R 1
J 0
(-5795 2095);
DISPLAY 0.872340 (-5795 2095);
PAINT GREEN (-5795 2095);
DISPLAY INVISIBLE (-5795 2095);
FORCEPROP 2 LAST CDS_LIB mstr_misc
J 0
(-5870 2320);
PAINT ORANGE (-5870 2320);
DISPLAY INVISIBLE (-5870 2320);
FORCEADD CAD_NOTE..1
(-3150 2350);
FORCEPROP 0 LAST L1 PLACE CAPS NEAR VCC PIN ON W25Q256 COMPONENT
J 0
(-3300 2225);
DISPLAY 0.808511 (-3300 2225);
PAINT ORANGE (-3300 2225);
FORCEPROP 2 LAST CDS_LIB mstr_symbols
J 0
(-3150 2350);
PAINT ORANGE (-3150 2350);
DISPLAY INVISIBLE (-3150 2350);
FORCEPROP 1 LAST COMMENT_BODY TRUE
J 0
(-3125 2450);
DISPLAY 0.978723 (-3125 2450);
PAINT ORANGE (-3125 2450);
DISPLAY INVISIBLE (-3125 2450);
WIRE 16 -1 (-3625 4250)(-3625 4300);
WIRE 16 -1 (-3925 4300)(-3625 4300);
WIRE 16 -1 (-3625 4400)(-3625 4300);
WIRE 16 -1 (-3925 4300)(-3925 4400);
WIRE 16 -1 (-3625 2150)(-3625 2200);
WIRE 16 -1 (-3625 2200)(-3925 2200);
WIRE 16 -1 (-3625 2300)(-3625 2200);
WIRE 16 -1 (-3925 2200)(-3925 2300);
WIRE 16 -1 (-1750 4425)(-1750 4575);
WIRE 16 -1 (-1550 4425)(-1750 4425);
WIRE 16 -1 (-6375 2675)(-6375 2550);
WIRE 16 -1 (-6375 2550)(-6175 2550);
WIRE 16 -1 (-6175 2550)(-5875 2550);
WIRE 16 -1 (-6175 2425)(-6175 2550);
WIRE 16 -1 (-5525 2550)(-5875 2550);
WIRE 16 -1 (-5875 2425)(-5875 2550);
WIRE 16 -1 (-5525 2550)(-5525 2075);
WIRE 16 -1 (-5525 2550)(-3925 2550);
WIRE 16 -1 (-3625 2550)(-3925 2550);
WIRE 16 -1 (-3925 2550)(-3925 2500);
WIRE 16 -1 (-5525 2075)(-5375 2075);
WIRE 16 -1 (-3625 2500)(-3625 2550);
WIRE 16 -1 (-1750 4125)(-1750 4025);
WIRE 16 -1 (-1750 3375)(-1750 3450);
WIRE 16 -1 (-1750 2325)(-1750 2475);
WIRE 16 -1 (-1550 2325)(-1750 2325);
WIRE 16 -1 (-1750 2025)(-1750 1925);
WIRE 16 -1 (-1750 1275)(-1750 1350);
WIRE 16 -1 (-4325 1525)(-4325 1450);
WIRE 16 -1 (-4525 1525)(-4325 1525);
WIRE 16 -1 (-4000 3725)(-4000 3650);
WIRE 16 -1 (-4150 3725)(-4000 3725);
WIRE 16 -1 (-6450 4775)(-6450 4650);
WIRE 16 -1 (-6450 4650)(-6250 4650);
WIRE 16 -1 (-6250 4650)(-5950 4650);
WIRE 16 -1 (-6250 4525)(-6250 4650);
WIRE 16 -1 (-5600 4650)(-5950 4650);
WIRE 16 -1 (-5950 4525)(-5950 4650);
WIRE 16 -1 (-5600 4650)(-5600 4175);
WIRE 16 -1 (-5600 4650)(-3925 4650);
WIRE 16 -1 (-3625 4650)(-3925 4650);
WIRE 16 -1 (-3925 4650)(-3925 4600);
WIRE 16 -1 (-5600 4175)(-5250 4175);
WIRE 16 -1 (-3625 4600)(-3625 4650);
WIRE 3 682 (-6150 3775)(-6775 3775);
WIRE 3 682 (-6150 3525)(-6150 3775);
WIRE 3 682 (-6775 3775)(-6775 3525);
WIRE 3 682 (-6775 3525)(-6150 3525);
WIRE 16 -1 (-5950 3675)(-5250 3675);
FORCEPROP 2 LAST SIG_NAME PU_SPI0_RST
J 0
(-5885 3685);
DISPLAY 0.638298 (-5885 3685);
PAINT ORANGE (-5885 3685);
FORCEPROP 2 LASTPROP $XRERR UNIQUE?
J 0
(-6125 3685);
DISPLAY 0.638298 (-6125 3685);
PAINT MONO (-6125 3685);
DISPLAY INVISIBLE (-6125 3685);
WIRE 16 -1 (-5950 4325)(-5950 3675);
WIRE 16 -1 (-7250 4075)(-5900 4075);
FORCEPROP 2 LAST SIG_NAME PU_BIOS_SPI_HOLD0_N
J 0
(-7225 4085);
DISPLAY 0.617021 (-7225 4085);
PAINT ORANGE (-7225 4085);
WIRE 16 -1 (-5900 4075)(-5250 4075);
WIRE 16 -1 (-6375 3075)(-5900 3075);
WIRE 16 -1 (-5900 3075)(-5900 4075);
WIRE 16 -1 (-6400 3350)(-6000 3350);
WIRE 16 -1 (-7250 4025)(-6000 4025);
FORCEPROP 2 LAST SIG_NAME PU_BIOS_SPI_WP0_N
J 0
(-7225 4035);
DISPLAY 0.617021 (-7225 4035);
PAINT ORANGE (-7225 4035);
WIRE 16 -1 (-6000 3350)(-6000 4025);
WIRE 16 -1 (-6000 4025)(-5250 4025);
WIRE 16 -1 (-5250 3975)(-6175 3975);
FORCEPROP 2 LAST SIG_NAME SPI_MISO_R0
J 0
(-5885 3985);
DISPLAY 0.638298 (-5885 3985);
PAINT ORANGE (-5885 3985);
FORCEPROP 2 LASTPROP $XRERR UNIQUE?
J 0
(-6125 3985);
DISPLAY 0.638298 (-6125 3985);
PAINT MONO (-6125 3985);
DISPLAY INVISIBLE (-6125 3985);
WIRE 16 -1 (-5250 3925)(-6425 3925);
FORCEPROP 2 LAST SIG_NAME SPI_SWITCH_MOSI_R0
J 0
(-5885 3935);
DISPLAY 0.638298 (-5885 3935);
PAINT ORANGE (-5885 3935);
FORCEPROP 2 LASTPROP $XRERR UNIQUE?
J 0
(-6125 3935);
DISPLAY 0.638298 (-6125 3935);
PAINT MONO (-6125 3935);
DISPLAY INVISIBLE (-6125 3935);
WIRE 16 -1 (-3725 4025)(-4150 4025);
FORCEPROP 2 LAST SIG_NAME TP_SPI_0_3
J 0
(-4085 4035);
DISPLAY 0.617021 (-4085 4035);
PAINT ORANGE (-4085 4035);
FORCEPROP 2 LASTPROP $XRERR UNIQUE?
J 0
(-3695 4025);
DISPLAY 0.638298 (-3695 4025);
PAINT MONO (-3695 4025);
DISPLAY INVISIBLE (-3695 4025);
WIRE 16 -1 (-3725 3875)(-4150 3875);
FORCEPROP 2 LAST SIG_NAME TP_SPI_0_0
J 0
(-4085 3885);
DISPLAY 0.617021 (-4085 3885);
PAINT ORANGE (-4085 3885);
FORCEPROP 2 LASTPROP $XRERR UNIQUE?
J 0
(-3695 3875);
DISPLAY 0.638298 (-3695 3875);
PAINT MONO (-3695 3875);
DISPLAY INVISIBLE (-3695 3875);
WIRE 16 -1 (-3725 4075)(-4150 4075);
FORCEPROP 2 LAST SIG_NAME TP_SPI_0_4
J 0
(-4085 4085);
DISPLAY 0.617021 (-4085 4085);
PAINT ORANGE (-4085 4085);
FORCEPROP 2 LASTPROP $XRERR UNIQUE?
J 0
(-3695 4075);
DISPLAY 0.638298 (-3695 4075);
PAINT MONO (-3695 4075);
DISPLAY INVISIBLE (-3695 4075);
WIRE 16 -1 (-1750 1550)(-1750 1650);
WIRE 16 -1 (-1750 1650)(-1750 1725);
WIRE 16 -1 (-1750 1650)(-700 1650);
FORCEPROP 2 LAST SIG_NAME PU_BIOS_SPI_WP1_N
J 2
(-750 1660);
DISPLAY 0.617021 (-750 1660);
PAINT ORANGE (-750 1660);
WIRE 16 -1 (-3975 2025)(-4525 2025);
FORCEPROP 2 LAST SIG_NAME TP_SPI_1_5
J 0
(-4360 2035);
DISPLAY 0.617021 (-4360 2035);
PAINT ORANGE (-4360 2035);
FORCEPROP 2 LASTPROP $XRERR UNIQUE?
J 0
(-3945 2025);
DISPLAY 0.638298 (-3945 2025);
PAINT MONO (-3945 2025);
DISPLAY INVISIBLE (-3945 2025);
WIRE 16 -1 (-3975 1975)(-4525 1975);
FORCEPROP 2 LAST SIG_NAME TP_SPI_1_4
J 0
(-4360 1985);
DISPLAY 0.617021 (-4360 1985);
PAINT ORANGE (-4360 1985);
FORCEPROP 2 LASTPROP $XRERR UNIQUE?
J 0
(-3945 1975);
DISPLAY 0.638298 (-3945 1975);
PAINT MONO (-3945 1975);
DISPLAY INVISIBLE (-3945 1975);
WIRE 16 -1 (-3975 1925)(-4525 1925);
FORCEPROP 2 LAST SIG_NAME TP_SPI_1_3
J 0
(-4360 1935);
DISPLAY 0.617021 (-4360 1935);
PAINT ORANGE (-4360 1935);
FORCEPROP 2 LASTPROP $XRERR UNIQUE?
J 0
(-3945 1925);
DISPLAY 0.638298 (-3945 1925);
PAINT MONO (-3945 1925);
DISPLAY INVISIBLE (-3945 1925);
WIRE 16 -1 (-3975 1875)(-4525 1875);
FORCEPROP 2 LAST SIG_NAME TP_SPI_1_2
J 0
(-4360 1885);
DISPLAY 0.617021 (-4360 1885);
PAINT ORANGE (-4360 1885);
FORCEPROP 2 LASTPROP $XRERR UNIQUE?
J 0
(-3945 1875);
DISPLAY 0.638298 (-3945 1875);
PAINT MONO (-3945 1875);
DISPLAY INVISIBLE (-3945 1875);
WIRE 16 -1 (-3975 1775)(-4525 1775);
FORCEPROP 2 LAST SIG_NAME TP_SPI_1_0
J 0
(-4360 1785);
DISPLAY 0.617021 (-4360 1785);
PAINT ORANGE (-4360 1785);
FORCEPROP 2 LASTPROP $XRERR UNIQUE?
J 0
(-3945 1775);
DISPLAY 0.638298 (-3945 1775);
PAINT MONO (-3945 1775);
DISPLAY INVISIBLE (-3945 1775);
WIRE 16 -1 (-6175 1875)(-7050 1875);
FORCEPROP 2 LAST SIG_NAME SPI_CS0_SECONDARY_R_N
J 0
(-7050 1885);
DISPLAY 0.617021 (-7050 1885);
PAINT ORANGE (-7050 1885);
WIRE 16 -1 (-6175 2225)(-6175 1875);
WIRE 16 -1 (-5375 1875)(-6175 1875);
WIRE 16 -1 (-5375 1725)(-6175 1725);
FORCEPROP 2 LAST SIG_NAME SPI_SWITCH_MOSI_R1
J 0
(-5975 1735);
DISPLAY 0.617021 (-5975 1735);
PAINT ORANGE (-5975 1735);
FORCEPROP 2 LASTPROP $XRERR UNIQUE?
J 0
(-6215 1735);
DISPLAY 0.638298 (-6215 1735);
PAINT MONO (-6215 1735);
DISPLAY INVISIBLE (-6215 1735);
WIRE 16 -1 (-6325 1200)(-5825 1200);
WIRE 16 -1 (-5825 1200)(-5825 1525);
WIRE 16 -1 (-5825 1525)(-5375 1525);
WIRE 16 -1 (-7050 1525)(-5825 1525);
FORCEPROP 2 LAST SIG_NAME PU_BIOS_SPI_HOLD1_N
J 0
(-7035 1535);
DISPLAY 0.617021 (-7035 1535);
PAINT ORANGE (-7035 1535);
WIRE 16 -1 (-7050 1575)(-5925 1575);
FORCEPROP 2 LAST SIG_NAME PU_BIOS_SPI_WP1_N
J 0
(-7050 1585);
DISPLAY 0.617021 (-7050 1585);
PAINT ORANGE (-7050 1585);
WIRE 16 -1 (-5925 1575)(-5375 1575);
WIRE 16 -1 (-5925 1425)(-5925 1575);
WIRE 16 -1 (-6325 1425)(-5925 1425);
WIRE 16 -1 (-5375 1675)(-6175 1675);
FORCEPROP 2 LAST SIG_NAME SPI_MISO_R1
J 2
(-5675 1685);
DISPLAY 0.617021 (-5675 1685);
PAINT ORANGE (-5675 1685);
FORCEPROP 2 LASTPROP $XRERR UNIQUE?
J 0
(-5915 1685);
DISPLAY 0.638298 (-5915 1685);
PAINT MONO (-5915 1685);
DISPLAY INVISIBLE (-5915 1685);
WIRE 16 -1 (-6175 1825)(-5375 1825);
FORCEPROP 2 LAST SIG_NAME SPI_CLK_R1
J 0
(-5835 1825);
DISPLAY 0.617021 (-5835 1825);
PAINT ORANGE (-5835 1825);
FORCEPROP 2 LASTPROP $XRERR UNIQUE?
J 0
(-6075 1825);
DISPLAY 0.638298 (-6075 1825);
PAINT MONO (-6075 1825);
DISPLAY INVISIBLE (-6075 1825);
WIRE 16 -1 (-7050 1675)(-6375 1675);
FORCEPROP 2 LAST SIG_NAME SPI_SWITCH_MISO
J 0
(-7050 1685);
DISPLAY 0.617021 (-7050 1685);
PAINT ORANGE (-7050 1685);
WIRE 16 -1 (-5875 1925)(-5375 1925);
FORCEPROP 0 LAST SIG_NAME PU_SPI1_RST
J 0
(-5760 1935);
DISPLAY 0.617021 (-5760 1935);
PAINT ORANGE (-5760 1935);
FORCEPROP 2 LASTPROP $XRERR UNIQUE?
J 0
(-6000 1935);
DISPLAY 0.638298 (-6000 1935);
PAINT MONO (-6000 1935);
DISPLAY INVISIBLE (-6000 1935);
WIRE 16 -1 (-5875 2225)(-5875 1925);
WIRE 16 -1 (-7300 1425)(-6525 1425);
FORCEPROP 2 LAST SIG_NAME SPI_BIOS_SOCKET_IO2
J 0
(-7260 1435);
DISPLAY 0.617021 (-7260 1435);
PAINT ORANGE (-7260 1435);
WIRE 16 -1 (-3725 3925)(-4150 3925);
FORCEPROP 2 LAST SIG_NAME TP_SPI_0_1
J 0
(-4085 3935);
DISPLAY 0.617021 (-4085 3935);
PAINT ORANGE (-4085 3935);
FORCEPROP 2 LASTPROP $XRERR UNIQUE?
J 0
(-3695 3925);
DISPLAY 0.638298 (-3695 3925);
PAINT MONO (-3695 3925);
DISPLAY INVISIBLE (-3695 3925);
WIRE 16 -1 (-3975 2075)(-4525 2075);
FORCEPROP 2 LAST SIG_NAME TP_SPI_1_6
J 0
(-4360 2085);
DISPLAY 0.617021 (-4360 2085);
PAINT ORANGE (-4360 2085);
FORCEPROP 2 LASTPROP $XRERR UNIQUE?
J 0
(-3945 2075);
DISPLAY 0.638298 (-3945 2075);
PAINT MONO (-3945 2075);
DISPLAY INVISIBLE (-3945 2075);
WIRE 16 -1 (-3975 1825)(-4525 1825);
FORCEPROP 2 LAST SIG_NAME TP_SPI_1_1
J 0
(-4360 1835);
DISPLAY 0.617021 (-4360 1835);
PAINT ORANGE (-4360 1835);
FORCEPROP 2 LASTPROP $XRERR UNIQUE?
J 0
(-3945 1825);
DISPLAY 0.638298 (-3945 1825);
PAINT MONO (-3945 1825);
DISPLAY INVISIBLE (-3945 1825);
WIRE 16 -1 (-7250 3925)(-6625 3925);
FORCEPROP 2 LAST SIG_NAME SPI_SWITCH_MOSI
J 0
(-7225 3935);
DISPLAY 0.617021 (-7225 3935);
PAINT ORANGE (-7225 3935);
WIRE 16 -1 (-7325 3350)(-6600 3350);
FORCEPROP 2 LAST SIG_NAME SPI_BIOS_SOCKET_IO2
J 0
(-7285 3360);
DISPLAY 0.617021 (-7285 3360);
PAINT ORANGE (-7285 3360);
WIRE 16 -1 (-6250 3625)(-6450 3625);
WIRE 16 -1 (-6250 3725)(-7250 3725);
FORCEPROP 2 LAST SIG_NAME SPI_CS0_PRIMARY_R_N
J 0
(-7225 3735);
DISPLAY 0.617021 (-7225 3735);
PAINT ORANGE (-7225 3735);
WIRE 16 -1 (-6250 3725)(-6250 3625);
WIRE 16 -1 (-5250 3725)(-6250 3725);
WIRE 16 -1 (-6250 4325)(-6250 3725);
WIRE 16 -1 (-6450 3825)(-5250 3825);
FORCEPROP 2 LAST SIG_NAME SPI_CLK_R0
J 0
(-5885 3835);
DISPLAY 0.638298 (-5885 3835);
PAINT ORANGE (-5885 3835);
FORCEPROP 2 LASTPROP $XRERR UNIQUE?
J 0
(-6125 3835);
DISPLAY 0.638298 (-6125 3835);
PAINT MONO (-6125 3835);
DISPLAY INVISIBLE (-6125 3835);
WIRE 16 -1 (-6650 3625)(-7250 3625);
FORCEPROP 2 LAST SIG_NAME SPI_SWITCH_CS0_N
J 0
(-7235 3635);
DISPLAY 0.638298 (-7235 3635);
PAINT ORANGE (-7235 3635);
WIRE 16 -1 (-7250 3825)(-6650 3825);
FORCEPROP 2 LAST SIG_NAME SPI_SWITCH_CLK
J 0
(-7225 3835);
DISPLAY 0.617021 (-7225 3835);
PAINT ORANGE (-7225 3835);
WIRE 16 -1 (-7250 3975)(-6375 3975);
FORCEPROP 2 LAST SIG_NAME SPI_SWITCH_MISO
J 0
(-7225 3985);
DISPLAY 0.617021 (-7225 3985);
PAINT ORANGE (-7225 3985);
WIRE 16 -1 (-7325 3075)(-6575 3075);
FORCEPROP 2 LAST SIG_NAME SPI_BIOS_SOCKET_IO3
J 0
(-7285 3085);
DISPLAY 0.617021 (-7285 3085);
PAINT ORANGE (-7285 3085);
WIRE 16 -1 (-1750 3650)(-1750 3750);
WIRE 16 -1 (-1750 3750)(-1750 3825);
WIRE 16 -1 (-1750 3750)(-700 3750);
FORCEPROP 2 LAST SIG_NAME PU_BIOS_SPI_WP0_N
J 2
(-750 3760);
DISPLAY 0.617021 (-750 3760);
PAINT ORANGE (-750 3760);
WIRE 16 -1 (-1350 4425)(-725 4425);
FORCEPROP 2 LAST SIG_NAME PU_BIOS_SPI_HOLD0_N
J 2
(-750 4435);
DISPLAY 0.617021 (-750 4435);
PAINT ORANGE (-750 4435);
WIRE 16 -1 (-7250 1200)(-6525 1200);
FORCEPROP 2 LAST SIG_NAME SPI_BIOS_SOCKET_IO3
J 0
(-7210 1210);
DISPLAY 0.617021 (-7210 1210);
PAINT ORANGE (-7210 1210);
WIRE 16 -1 (-7050 1825)(-6375 1825);
FORCEPROP 2 LAST SIG_NAME SPI_SWITCH_CLK
J 0
(-7050 1835);
DISPLAY 0.617021 (-7050 1835);
PAINT ORANGE (-7050 1835);
WIRE 16 -1 (-3725 4175)(-4150 4175);
FORCEPROP 2 LAST SIG_NAME TP_SPI_0_6
J 0
(-4085 4185);
DISPLAY 0.617021 (-4085 4185);
PAINT ORANGE (-4085 4185);
FORCEPROP 2 LASTPROP $XRERR UNIQUE?
J 0
(-3695 4175);
DISPLAY 0.638298 (-3695 4175);
PAINT MONO (-3695 4175);
DISPLAY INVISIBLE (-3695 4175);
WIRE 16 -1 (-3725 4125)(-4150 4125);
FORCEPROP 2 LAST SIG_NAME TP_SPI_0_5
J 0
(-4085 4135);
DISPLAY 0.617021 (-4085 4135);
PAINT ORANGE (-4085 4135);
FORCEPROP 2 LASTPROP $XRERR UNIQUE?
J 0
(-3695 4125);
DISPLAY 0.638298 (-3695 4125);
PAINT MONO (-3695 4125);
DISPLAY INVISIBLE (-3695 4125);
WIRE 16 -1 (-3725 3975)(-4150 3975);
FORCEPROP 2 LAST SIG_NAME TP_SPI_0_2
J 0
(-4085 3985);
DISPLAY 0.617021 (-4085 3985);
PAINT ORANGE (-4085 3985);
FORCEPROP 2 LASTPROP $XRERR UNIQUE?
J 0
(-3695 3975);
DISPLAY 0.638298 (-3695 3975);
PAINT MONO (-3695 3975);
DISPLAY INVISIBLE (-3695 3975);
WIRE 16 -1 (-7050 1725)(-6375 1725);
FORCEPROP 2 LAST SIG_NAME SPI_SWITCH_MOSI
J 0
(-7050 1735);
DISPLAY 0.617021 (-7050 1735);
PAINT ORANGE (-7050 1735);
WIRE 16 -1 (-1350 2325)(-725 2325);
FORCEPROP 2 LAST SIG_NAME PU_BIOS_SPI_HOLD1_N
J 2
(-750 2335);
DISPLAY 0.617021 (-750 2335);
PAINT ORANGE (-750 2335);
DOT 1 (-5900 4075);
DOT 1 (-5925 1575);
DOT 1 (-6175 1875);
DOT 1 (-5825 1525);
DOT 1 (-3625 4300);
DOT 1 (-3925 4650);
DOT 1 (-5875 2550);
DOT 1 (-1750 3750);
DOT 1 (-1750 1650);
DOT 1 (-3625 2200);
DOT 1 (-5600 4650);
DOT 1 (-5950 4650);
DOT 1 (-5525 2550);
DOT 1 (-6175 2550);
DOT 1 (-6000 4025);
DOT 1 (-6250 4650);
DOT 1 (-6250 3725);
DOT 1 (-3925 2550);
FORCENOTE
U7F1 IS SOCKET.
(-5200 3350) 0;
DISPLAY LEFT (-5200 3350);
DISPLAY 1.021277 (-5200 3350);
PAINT PURPLE (-5200 3350);
FORCENOTE
ROOM=SM_MEM
(-7890 186) 0;
DISPLAY LEFT (-7890 186);
DISPLAY 0.765957 (-7890 186);
PAINT PURPLE (-7890 186);
FORCENOTE
TP FAB3 ADD RES 1017
(-6775 3475) 0;
DISPLAY LEFT (-6775 3475);
DISPLAY 0.638298 (-6775 3475);
PAINT RED (-6775 3475);
FORCENOTE
SECONDARY FLASH - BOTTOM SIDE OF BOARD
(-5600 2675) 0;
DISPLAY LEFT (-5600 2675);
DISPLAY 1.021277 (-5600 2675);
PAINT PURPLE (-5600 2675);
FORCENOTE
PRIMARY FLASH - TOP SIDE OF BOARD
(-5500 4800) 0;
DISPLAY LEFT (-5500 4800);
DISPLAY 1.021277 (-5500 4800);
PAINT PURPLE (-5500 4800);
QUIT
